G04 ================== begin FILE IDENTIFICATION RECORD ==================*
G04 Layout Name:  9324_DA0F0TMBIJ0_F0T_Motherboard_J_v01_20230324_0910.brd*
G04 Film Name:    smb*
G04 File Format:  Gerber RS274X*
G04 File Origin:  Cadence Allegro 17.2-S081*
G04 Origin Date:  Sat Mar 25 08:44:52 2023*
G04 *
G04 Layer:  DRAWING FORMAT/TITLE_BLOCK_A*
G04 Layer:  DRAWING FORMAT/TITLE_BLOCK*
G04 Layer:  VIA CLASS/SOLDERMASK_BOTTOM*
G04 Layer:  PIN/SOLDERMASK_BOTTOM*
G04 Layer:  PACKAGE GEOMETRY/SOLDERMASK_BOTTOM*
G04 Layer:  MANUFACTURING/PHOTOPLOT_OUTLINE*
G04 Layer:  DRAWING FORMAT/TITLE_DATA_SMB*
G04 Layer:  BOARD GEOMETRY/SOLDERMASK_BOTTOM*
G04 *
G04 Offset:    (0.00 0.00)*
G04 Mirror:    No*
G04 Mode:      Positive*
G04 Rotation:  0*
G04 FullContactRelief:  No*
G04 UndefLineWidth:     6.00*
G04 ================== end FILE IDENTIFICATION RECORD ====================*
%FSLAX25Y25*MOIN*%
%IR0*IPPOS*OFA0.00000B0.00000*MIA0B0*SFA1.00000B1.00000*%
%AMMACRO100*
21,1,.032,.036,0.0,0.0,135.*%
%ADD100MACRO100*%
%ADD49R,.13X.064*%
%ADD84O,.141X.068*%
%ADD19O,.115X.066*%
%ADD11C,.03*%
%ADD80C,.04*%
%ADD50C,.022*%
%ADD92C,.05*%
%ADD33C,.032*%
%ADD60R,.024X.009*%
%ADD32C,.024*%
%ADD31C,.06*%
%ADD76C,.034*%
%ADD69C,.061*%
%ADD61R,.009X.024*%
%ADD86C,.0233*%
%ADD27C,.064*%
%ADD57C,.065*%
%ADD37R,.115X.099*%
%ADD90R,.134X.099*%
%ADD41R,.099X.115*%
%ADD35C,.066*%
%ADD64C,.085*%
%ADD26C,.068*%
%ADD44C,.03417*%
%AMMACRO89*
4,1,8,.0445,-.08,
.0445,.08,
-.0445,.08,
-.0445,.0216,
-.0165,.0216,
-.0165,-.0216,
-.0445,-.0216,
-.0445,-.08,
.0445,-.08,
0.0*
%
%ADD89MACRO89*%
%ADD107C,.0395*%
%ADD39R,.064X.064*%
%ADD58R,.065X.065*%
%AMMACRO85*
4,1,30,-.08273,-.12417,
-.100642,-.108127,
-.115497,-.089217,
-.126842,-.068015,
-.134333,-.045165,
-.137743,-.021362,
-.136967,.002672,
-.132029,.026206,
-.12308,.048525,
-.110391,.068951,
-.094348,.086864,
-.075439,.101718,
-.054237,.113063,
-.031387,.120554,
-.007583,.123964,
.016451,.123188,
.039985,.118251,
.062304,.109302,
.08273,.096613,
.100642,.08057,
.115497,.06166,
.126842,.040458,
.134333,.017608,
.137743,-.006195,
.136967,-.030229,
.132029,-.053763,
.12308,-.076082,
.110391,-.096509,
.094348,-.114421,
.08273,-.12417,
-.08273,-.12417,
0.0*
%
%ADD85MACRO85*%
%ADD36R,.066X.066*%
%ADD106C,.0785*%
%ADD93R,.068X.068*%
%ADD46R,.03417X.03417*%
%ADD45C,.02787*%
%AMMACRO96*
4,1,28,.00426,.01259,
.003485,.013262,
.002602,.013784,
.001641,.014146,
.000633,.014335,
-.000393,.014346,
-.001405,.014178,
-.002373,.013838,
-.003267,.013334,
-.004061,.012683,
-.00411,.01264,
-.00942,.00733,
-.00775,.00566,
-.01513,-.00172,
-.00172,-.01513,
.00566,-.00775,
.00733,-.00942,
.01264,-.00411,
.013297,-.003321,
.01381,-.002433,
.014162,-.001469,
.01434,-.000458,
.014341,.000568,
.014163,.001578,
.013812,.002543,
.0133,.003431,
.01264,.004218,
.01259,.00426,
.00426,.01259,
0.0*
%
%ADD96MACRO96*%
%AMMACRO66*
4,1,8,.0034,.0082,
-.0034,.0082,
-.0082,.0034,
-.0082,-.00341,
-.00341,-.0082,
.0034,-.0082,
.0082,-.0034,
.0082,.0034,
.0034,.0082,
0.0*
%
%ADD66MACRO66*%
%AMMACRO29*
4,1,28,-.00589,.01192,
-.006913,.011842,
-.007907,.011587,
-.008842,.011163,
-.009688,.010584,
-.010422,.009866,
-.011019,.009032,
-.011463,.008107,
-.011739,.007119,
-.01184,.006097,
-.01184,.00603,
-.01184,-.00148,
-.00948,-.00148,
-.00948,-.01191,
.00948,-.01191,
.00948,-.00148,
.01184,-.00148,
.01184,.00603,
.011751,.007052,
.011486,.008044,
.011053,.008974,
.010465,.009815,
.00974,.010541,
.0089,.01113,
.00797,.011564,
.006979,.01183,
.005957,.01192,
.00589,.01192,
-.00589,.01192,
0.0*
%
%ADD29MACRO29*%
%ADD79C,.06974*%
%AMMACRO65*
4,1,8,.0082,-.0034,
.0082,.0034,
.0034,.0082,
-.00341,.0082,
-.0082,.00341,
-.0082,-.0034,
-.0034,-.0082,
.0034,-.0082,
.0082,-.0034,
0.0*
%
%ADD65MACRO65*%
%ADD43C,.03968*%
%AMMACRO18*
4,1,28,.01192,.00589,
.011842,.006913,
.011587,.007907,
.011163,.008842,
.010584,.009688,
.009866,.010422,
.009032,.011019,
.008107,.011463,
.007119,.011739,
.006097,.01184,
.00603,.01184,
-.00148,.01184,
-.00148,.00948,
-.01191,.00948,
-.01191,-.00948,
-.00148,-.00948,
-.00148,-.01184,
.00603,-.01184,
.007052,-.011751,
.008044,-.011486,
.008974,-.011053,
.009815,-.010465,
.010541,-.00974,
.01113,-.0089,
.011564,-.00797,
.01183,-.006979,
.01192,-.005957,
.01192,-.00589,
.01192,.00589,
0.0*
%
%ADD18MACRO18*%
%AMMACRO95*
4,1,28,-.00425,-.01259,
-.003472,-.013259,
-.002588,-.01378,
-.001628,-.01414,
-.000619,-.014328,
.000407,-.014338,
.001419,-.01417,
.002387,-.013828,
.00328,-.013323,
.004072,-.012671,
.00412,-.01263,
.00943,-.00732,
.00776,-.00565,
.01513,.00173,
.00173,.01513,
-.00565,.00776,
-.00732,.00943,
-.01263,.00412,
-.013288,.003332,
-.013802,.002444,
-.014154,.00148,
-.014333,.00047,
-.014334,-.000556,
-.014157,-.001567,
-.013807,-.002531,
-.013295,-.003421,
-.012636,-.004207,
-.01259,-.00425,
-.00425,-.01259,
0.0*
%
%ADD95MACRO95*%
%AMMACRO28*
4,1,28,.0059,-.01191,
.006923,-.01183,
.007916,-.011573,
.00885,-.011148,
.009696,-.010567,
.010428,-.009849,
.011024,-.009013,
.011466,-.008088,
.011741,-.007099,
.01184,-.006078,
.01184,-.00602,
.01184,.00149,
.00948,.00149,
.00948,.01192,
-.00948,.01192,
-.00948,.00149,
-.01184,.00149,
-.01184,-.00602,
-.011751,-.007042,
-.011486,-.008033,
-.011053,-.008964,
-.010465,-.009805,
-.00974,-.010531,
-.0089,-.01112,
-.007971,-.011554,
-.00698,-.01182,
-.005958,-.01191,
-.0059,-.01191,
.0059,-.01191,
0.0*
%
%ADD28MACRO28*%
%AMMACRO17*
4,1,28,-.01191,-.0059,
-.01183,-.006923,
-.011573,-.007916,
-.011148,-.00885,
-.010567,-.009696,
-.009849,-.010428,
-.009013,-.011024,
-.008088,-.011466,
-.007099,-.011741,
-.006078,-.01184,
-.00602,-.01184,
.00149,-.01184,
.00149,-.00948,
.01192,-.00948,
.01192,.00948,
.00149,.00948,
.00149,.01184,
-.00602,.01184,
-.007042,.011751,
-.008033,.011486,
-.008964,.011053,
-.009805,.010465,
-.010531,.00974,
-.01112,.0089,
-.011554,.007971,
-.01182,.00698,
-.01191,.005958,
-.01191,.0059,
-.01191,-.0059,
0.0*
%
%ADD17MACRO17*%
%ADD87R,.06974X.06974*%
%ADD21R,.05X.021*%
%ADD94R,.07X.021*%
%ADD51R,.021X.024*%
%ADD38R,.024X.022*%
%ADD63R,.022X.024*%
%ADD62R,.06X.06*%
%ADD30R,.011X.036*%
%ADD16R,.028X.011*%
%ADD71R,.024X.016*%
%ADD52R,.036X.032*%
%ADD88R,.132X.139*%
%ADD82R,.056X.022*%
%ADD54R,.032X.036*%
%ADD20R,.05X.028*%
%AMMACRO104*
21,1,.016,.0081,0.0,0.0,135.*%
%ADD104MACRO104*%
%ADD98C,.142*%
%ADD72R,.058X.03*%
%AMMACRO105*
21,1,.016,.019,0.0,0.0,45.*%
%ADD105MACRO105*%
%AMMACRO101*
21,1,.044,.054,0.0,0.0,45.*%
%ADD101MACRO101*%
%ADD56C,.26*%
%ADD53R,.019X.016*%
%ADD34R,.03X.058*%
%ADD25R,.054X.044*%
%ADD83C,.162*%
%ADD73R,.063X.018*%
%ADD59R,.016X.019*%
%ADD42O,.319X.256*%
%ADD40R,.044X.054*%
%ADD13C,.414*%
%ADD74R,.044X.019*%
%ADD14C,.145*%
%ADD12C,.118*%
%ADD48C,.155*%
%ADD78R,.048X.018*%
%ADD77C,.237*%
%ADD47C,.319*%
%AMMACRO70*
4,1,8,-.0445,.08,
-.0445,-.08,
.0445,-.08,
.0445,-.0216,
.0165,-.0216,
.0165,.0216,
.0445,.0216,
.0445,.08,
-.0445,.08,
0.0*
%
%ADD70MACRO70*%
%ADD91R,.058X.048*%
%ADD81C,.178*%
%ADD75C,.295*%
%ADD55R,.048X.058*%
%ADD10C,.398*%
%AMMACRO97*
4,1,28,-.00426,-.01259,
-.003485,-.013262,
-.002602,-.013784,
-.001641,-.014146,
-.000633,-.014335,
.000393,-.014346,
.001405,-.014178,
.002373,-.013838,
.003267,-.013334,
.004061,-.012683,
.00411,-.01264,
.00942,-.00733,
.00775,-.00566,
.01513,.00172,
.00172,.01513,
-.00566,.00775,
-.00733,.00942,
-.01264,.00411,
-.013297,.003321,
-.01381,.002433,
-.014162,.001469,
-.01434,.000458,
-.014341,-.000568,
-.014163,-.001578,
-.013812,-.002543,
-.0133,-.003431,
-.01264,-.004218,
-.01259,-.00426,
-.00426,-.01259,
0.0*
%
%ADD97MACRO97*%
%AMMACRO68*
4,1,8,-.0034,-.0082,
.0034,-.0082,
.0082,-.0034,
.0082,.00341,
.00341,.0082,
-.0034,.0082,
-.0082,.0034,
-.0082,-.0034,
-.0034,-.0082,
0.0*
%
%ADD68MACRO68*%
%AMMACRO67*
4,1,8,-.0082,.0034,
-.0082,-.0034,
-.0034,-.0082,
.00341,-.0082,
.0082,-.00341,
.0082,.0034,
.0034,.0082,
-.0034,.0082,
-.0082,.0034,
0.0*
%
%ADD67MACRO67*%
%AMMACRO22*
4,1,28,.00589,-.01192,
.006913,-.011842,
.007907,-.011587,
.008842,-.011163,
.009688,-.010584,
.010422,-.009866,
.011019,-.009032,
.011463,-.008107,
.011739,-.007119,
.01184,-.006097,
.01184,-.00603,
.01184,.00148,
.00948,.00148,
.00948,.01191,
-.00948,.01191,
-.00948,.00148,
-.01184,.00148,
-.01184,-.00603,
-.011751,-.007052,
-.011486,-.008044,
-.011053,-.008974,
-.010465,-.009815,
-.00974,-.010541,
-.0089,-.01113,
-.00797,-.011564,
-.006979,-.01183,
-.005957,-.01192,
-.00589,-.01192,
.00589,-.01192,
0.0*
%
%ADD22MACRO22*%
%AMMACRO15*
4,1,28,-.01192,-.00589,
-.011842,-.006913,
-.011587,-.007907,
-.011163,-.008842,
-.010584,-.009688,
-.009866,-.010422,
-.009032,-.011019,
-.008107,-.011463,
-.007119,-.011739,
-.006097,-.01184,
-.00603,-.01184,
.00148,-.01184,
.00148,-.00948,
.01191,-.00948,
.01191,.00948,
.00148,.00948,
.00148,.01184,
-.00603,.01184,
-.007052,.011751,
-.008044,.011486,
-.008974,.011053,
-.009815,.010465,
-.010541,.00974,
-.01113,.0089,
-.011564,.00797,
-.01183,.006979,
-.01192,.005957,
-.01192,.00589,
-.01192,-.00589,
0.0*
%
%ADD15MACRO15*%
%AMMACRO103*
4,1,28,-.00738,-.01106,
-.006799,-.011906,
-.006082,-.01264,
-.005248,-.013238,
-.004323,-.013682,
-.003335,-.013958,
-.002314,-.014059,
-.001291,-.013981,
-.000297,-.013727,
.000638,-.013304,
.0007,-.01327,
.0072,-.00951,
.00602,-.00747,
.01505,-.00225,
.00557,.01417,
-.00346,.00895,
-.00464,.01099,
-.01114,.00724,
-.011981,.006652,
-.012707,.005927,
-.013297,.005087,
-.013732,.004158,
-.013998,.003167,
-.014089,.002145,
-.014001,.001123,
-.013736,.000131,
-.013304,-.000799,
-.01327,-.00086,
-.00738,-.01106,
0.0*
%
%ADD103MACRO103*%
%AMMACRO99*
4,1,28,.00425,.01259,
.003472,.013259,
.002588,.01378,
.001628,.01414,
.000619,.014328,
-.000407,.014338,
-.001419,.01417,
-.002387,.013828,
-.00328,.013323,
-.004072,.012671,
-.00412,.01263,
-.00943,.00732,
-.00776,.00565,
-.01513,-.00173,
-.00173,-.01513,
.00565,-.00776,
.00732,-.00943,
.01263,-.00412,
.013288,-.003332,
.013802,-.002444,
.014154,-.00148,
.014333,-.00047,
.014334,.000556,
.014157,.001567,
.013807,.002531,
.013295,.003421,
.012636,.004207,
.01259,.00425,
.00425,.01259,
0.0*
%
%ADD99MACRO99*%
%AMMACRO24*
4,1,28,.01191,.0059,
.01183,.006923,
.011573,.007916,
.011148,.00885,
.010567,.009696,
.009849,.010428,
.009013,.011024,
.008088,.011466,
.007099,.011741,
.006078,.01184,
.00602,.01184,
-.00149,.01184,
-.00149,.00948,
-.01192,.00948,
-.01192,-.00948,
-.00149,-.00948,
-.00149,-.01184,
.00602,-.01184,
.007042,-.011751,
.008033,-.011486,
.008964,-.011053,
.009805,-.010465,
.010531,-.00974,
.01112,-.0089,
.011554,-.007971,
.01182,-.00698,
.01191,-.005958,
.01191,-.0059,
.01191,.0059,
0.0*
%
%ADD24MACRO24*%
%AMMACRO23*
4,1,28,-.0059,.01191,
-.006923,.01183,
-.007916,.011573,
-.00885,.011148,
-.009696,.010567,
-.010428,.009849,
-.011024,.009013,
-.011466,.008088,
-.011741,.007099,
-.01184,.006078,
-.01184,.00602,
-.01184,-.00149,
-.00948,-.00149,
-.00948,-.01192,
.00948,-.01192,
.00948,-.00149,
.01184,-.00149,
.01184,.00602,
.011751,.007042,
.011486,.008033,
.011053,.008964,
.010465,.009805,
.00974,.010531,
.0089,.01112,
.007971,.011554,
.00698,.01182,
.005958,.01191,
.0059,.01191,
-.0059,.01191,
0.0*
%
%ADD23MACRO23*%
%AMMACRO102*
4,1,28,.00736,.01107,
.006779,.011915,
.006059,.012647,
.005223,.013242,
.004297,.013683,
.003308,.013957,
.002287,.014054,
.001264,.013973,
.000271,.013716,
-.000663,.01329,
-.00071,.01326,
-.00721,.00951,
-.00603,.00746,
-.01506,.00225,
-.00558,-.01417,
.00345,-.00895,
.00463,-.011,
.01113,-.00724,
.011973,-.006656,
.012699,-.005931,
.013289,-.005091,
.013723,-.004162,
.01399,-.003171,
.01408,-.002149,
.013992,-.001127,
.013727,-.000135,
.013295,.000795,
.01326,.00085,
.00736,.01107,
0.0*
%
%ADD102MACRO102*%
%ADD108C,.01*%
%ADD109C,.006*%
%ADD110C,.1582*%
G75*
%LPD*%
G75*
G36*
G01X38270Y147842D02*
G03I-5900J0D01*
G37*
G36*
G01X52380Y1574922D02*
G03I-5900J0D01*
G37*
G36*
G01X55375Y124912D02*
G02X66445Y113077I5535J-5917D01*
G01X61845Y108774D01*
G02X50775Y120609I-5535J5917D01*
G01X55375Y124912D01*
G37*
G36*
G01X198098Y260082D02*
G02X156728I-20685J0D01*
G01Y294334D01*
G02X198098I20685J0D01*
G01Y260082D01*
G37*
G36*
G01X197996Y1644764D02*
G02X156626I-20685J0D01*
G01Y1671142D01*
G02X197996I20685J0D01*
G01Y1644764D01*
G37*
G36*
G01X156626D02*
Y1671142D01*
G02X197996I20685J0D01*
G01Y1644764D01*
G02X156626I-20685J0D01*
G37*
G36*
G01X683500Y260110D02*
Y294362D01*
G02X724870I20685J0D01*
G01Y260110D01*
G02X683500I-20685J0D01*
G37*
G36*
G01X825575Y204724D02*
G02I-19885J0D01*
G37*
G36*
G01X857240Y1420330D02*
G02I-16000J0D01*
G37*
G36*
G01X948624Y321653D02*
G02I-19885J0D01*
G37*
G36*
G01X934800Y1185132D02*
G03I-5900J0D01*
G37*
G36*
G01X1032240Y1420330D02*
G02I-16000J0D01*
G37*
G36*
G01X1077543Y204724D02*
G02I-19885J0D01*
G37*
G36*
G01X1174240Y260082D02*
G02X1132870I-20685J0D01*
G01Y294334D01*
G02X1174240I20685J0D01*
G01Y260082D01*
G37*
G36*
G01X1659642Y260110D02*
Y294362D01*
G02X1701012I20685J0D01*
G01Y260110D01*
G02X1659642I-20685J0D01*
G37*
G36*
G01X1700917Y1671142D02*
Y1644764D01*
G02X1659547I-20685J0D01*
G01Y1671142D01*
G02X1700917I20685J0D01*
G37*
G36*
G01X1732200Y1710102D02*
G03I-5900J0D01*
G37*
G36*
G01X1776979Y1714960D02*
G02I-10050J0D01*
G37*
G36*
G01X1802140Y126972D02*
G03I-5900J0D01*
G37*
G36*
G01X1837827Y127165D02*
G02X1821622I-8103J0D01*
G01Y133465D01*
G02X1837827I8103J0D01*
G01Y127165D01*
G37*
%LPC*%
G75*
G54D110*
X1766929Y1714960D03*
%LPD*%
G75*
G54D100*
X1297819Y250945D03*
X1297799Y258931D03*
X1293697Y254829D03*
X1293949Y262857D03*
X1289847Y258755D03*
X1301921Y255047D03*
G54D101*
X1307199Y240916D03*
X1312149Y245866D03*
X1301906Y246041D03*
X1306856Y250991D03*
G54D102*
X1343332Y175405D03*
G54D103*
X1340763Y173921D03*
G54D10*
X27559Y87795D03*
X40708Y631890D03*
Y1368897D03*
X51181Y1714961D03*
X373622Y87795D03*
X395670Y1714961D03*
X661023Y631890D03*
X707677Y1714961D03*
X800787Y87795D03*
X931692Y757874D03*
Y1072834D03*
Y1387795D03*
X1045865Y87795D03*
X1155708Y1714961D03*
X1271260Y631890D03*
X1461805Y1714961D03*
X1499606Y87795D03*
X1816771Y631890D03*
Y1368897D03*
X1806299Y1714961D03*
X1829921Y87795D03*
G54D104*
X1339045Y207575D03*
G54D20*
X37721Y754822D03*
Y763090D03*
X54847Y754822D03*
Y763090D03*
X1446071Y732802D03*
Y741070D03*
X1463197Y732802D03*
Y741070D03*
G54D11*
X14092Y287115D03*
X16925Y203366D03*
X17061Y196368D03*
X24720Y216362D03*
Y232362D03*
Y224362D03*
Y240362D03*
X29962Y401000D03*
X27520Y434992D03*
X30200Y754822D03*
X24647Y1262074D03*
X26050Y1252272D03*
X33500Y200862D03*
X33670Y192862D03*
Y208362D03*
Y232362D03*
X42500Y224409D03*
X33670Y240362D03*
X40000Y298707D03*
Y293392D03*
X36255Y304972D03*
X39320Y392269D03*
X40940Y387302D03*
X44350Y400582D03*
X38620Y447202D03*
X38340Y440992D03*
X33350Y434992D03*
X39000Y731600D03*
X48697Y952481D03*
Y959331D03*
X39505Y987865D03*
X39927Y1249845D03*
X40217Y1258925D03*
X47190Y1252034D03*
X47567Y1246625D03*
X48269Y1672771D03*
X54920Y185039D03*
Y177165D03*
X62020Y295952D03*
X53825Y421746D03*
X57920Y443702D03*
X55564Y449734D03*
X57595Y603476D03*
X51878Y733922D03*
X61539Y756113D03*
X63487Y761105D03*
X60997Y768875D03*
X54620Y1258892D03*
X56777Y1252098D03*
Y1314165D03*
X54478Y1663669D03*
X54535Y1658447D03*
X53333Y1671862D03*
X65000Y1681900D03*
X58325Y1679275D03*
X65881Y305426D03*
X71500Y390812D03*
X71772Y421746D03*
X75490Y432519D03*
X72981Y466385D03*
X80300Y641862D03*
X80241Y659011D03*
X80123Y664031D03*
X80135Y667933D03*
X74559Y667814D03*
X76565Y717949D03*
X78397Y952481D03*
Y959331D03*
X70852Y1250055D03*
X69877Y1259125D03*
X76890Y1252034D03*
X65600Y1318588D03*
X65240Y1326068D03*
X74100Y1613300D03*
X86490Y200787D03*
Y208661D03*
X85960Y224409D03*
X85788Y240157D03*
X87620Y285321D03*
X87845Y278798D03*
Y295798D03*
X87820Y302821D03*
X87654Y376026D03*
X87520Y386502D03*
X85826Y420319D03*
X84410Y438519D03*
X94811Y510173D03*
X93069Y631917D03*
X90565Y636612D03*
X97560Y637624D03*
X91027Y643276D03*
X95725Y654540D03*
X95860Y659622D03*
X83165Y652564D03*
X91078Y649584D03*
X83208Y646436D03*
X83004Y705141D03*
X97295Y699786D03*
X90000Y766798D03*
X85747Y994357D03*
X92630Y1251615D03*
X84390Y1258982D03*
X82241Y1252037D03*
X87450Y1251692D03*
X81900Y1613300D03*
X85800D03*
X96420Y1693803D03*
X113490Y216596D03*
X113400Y232128D03*
X107200Y393562D03*
X107301Y388071D03*
X101317Y431727D03*
X110756Y465968D03*
X113597Y488434D03*
X107419Y487807D03*
X112480Y507792D03*
X110689Y498271D03*
X112590Y503248D03*
X99773Y515606D03*
X98490Y629496D03*
X102269Y634466D03*
X107045Y661917D03*
X99021Y663732D03*
X103397Y667272D03*
X101512Y702939D03*
X98134Y722501D03*
X107852Y767065D03*
X108097Y952481D03*
Y959331D03*
X98905Y987865D03*
X100287Y1249926D03*
X99577Y1259125D03*
X106590Y1252034D03*
X109320Y1246422D03*
X103902Y1584337D03*
X104318Y1589352D03*
X100620Y1596367D03*
X100020Y1615821D03*
X104400Y1632385D03*
X104318Y1637862D03*
X99600Y1668332D03*
X99645Y1663217D03*
X99980Y1698921D03*
X115850Y186362D03*
X122000Y207362D03*
X116920Y207462D03*
X114087Y285495D03*
X118920Y278875D03*
X114087Y302854D03*
X119220Y306236D03*
X125007Y384071D03*
Y396071D03*
X119457Y392071D03*
X114507Y404571D03*
X128145Y453722D03*
X125070Y486736D03*
X124124Y495883D03*
X118652Y528860D03*
X129762Y531942D03*
X117430Y636052D03*
X114021Y669409D03*
X116567Y763774D03*
X130147Y1249975D03*
X129277Y1259125D03*
X114020Y1259032D03*
X114604Y1251348D03*
X118927Y1308685D03*
X118727Y1316695D03*
X123220Y1324662D03*
X116798Y1589352D03*
X119500Y1622380D03*
X124795Y1681846D03*
X128195Y1674362D03*
X127195Y1696362D03*
Y1704362D03*
X117426Y1726622D03*
X125720Y1719262D03*
X132490Y420062D03*
X138042Y480238D03*
X132833D03*
X139370Y492560D03*
X136982Y497090D03*
X131737Y496295D03*
X131295Y487822D03*
X137672Y502106D03*
X135428Y510312D03*
X138878Y512550D03*
X138408Y507366D03*
X139153Y516453D03*
X132600Y537072D03*
X131740Y640103D03*
X130530Y658172D03*
X130570Y653162D03*
X131600Y646861D03*
X130325Y699824D03*
Y708624D03*
Y717424D03*
X145181Y950660D03*
X145485Y959265D03*
X145147Y994357D03*
X136010Y1249882D03*
X141641Y1252037D03*
X144359Y1246662D03*
X143680Y1262582D03*
X145087Y1343175D03*
X144263Y1412275D03*
X136518Y1602410D03*
X136522Y1598410D03*
X137420Y1708362D03*
X144520Y1717562D03*
X134557Y1722778D03*
X137852Y1726572D03*
X154220Y375682D03*
X160090Y391170D03*
Y397470D03*
X152826Y439397D03*
Y434362D03*
X156306Y449045D03*
X161267Y503143D03*
X151378Y526924D03*
X149400Y766798D03*
X160465Y985165D03*
X159780Y1241732D03*
X157610Y1246842D03*
X158977Y1259125D03*
X159587Y1403924D03*
X152026Y1614138D03*
X158335Y1614452D03*
X161310Y1708022D03*
X148145Y1701862D03*
X173275Y393497D03*
X164000Y415362D03*
X163926Y425383D03*
X164000Y420362D03*
X163926Y430883D03*
Y443319D03*
X178546Y453806D03*
X174881Y950660D03*
X175185Y959265D03*
X164976Y1226342D03*
X165990Y1252034D03*
X171341Y1252037D03*
X173770Y1260192D03*
X176560Y1251812D03*
X171262Y1443390D03*
X164920Y1712017D03*
X163060Y1717017D03*
X178226Y1726517D03*
X172962Y1721234D03*
X169777Y1726517D03*
X178142Y1720652D03*
X187371Y425383D03*
Y430883D03*
X194440Y433895D03*
Y439565D03*
X193110Y672272D03*
X179100Y766798D03*
X188493Y1251400D03*
X188307Y1260475D03*
X182000Y1251762D03*
X182587Y1343945D03*
X193293Y1722197D03*
X188794Y1725092D03*
X204699Y423242D03*
Y428742D03*
X205251Y577002D03*
X204610Y571097D03*
X205251Y611002D03*
X198336Y608271D03*
X199164Y616481D03*
X205251Y642969D03*
X200654Y646271D03*
X200018Y677492D03*
X199541Y684554D03*
X208787Y768035D03*
X204332Y950909D03*
X205627Y959575D03*
X197317Y989785D03*
X203040Y1262074D03*
X195690Y1252034D03*
X201041Y1252037D03*
X209390Y1250614D03*
X197460Y1404675D03*
X203120Y1624782D03*
X208115Y1624217D03*
X195590Y1714517D03*
X196010Y1709017D03*
X208295Y1703362D03*
X199050Y1726431D03*
X224210Y431501D03*
X224305Y422977D03*
X219995Y426267D03*
X224210Y436619D03*
X218140Y440735D03*
X218010Y432735D03*
X223664Y443125D03*
X220000Y448735D03*
X212891Y566632D03*
X218159Y776523D03*
X218197Y952481D03*
Y959331D03*
X225057Y989205D03*
X226910Y1227939D03*
X218590Y1251362D03*
X219660Y1260492D03*
X225390Y1252034D03*
X221637Y1316075D03*
X223387Y1336305D03*
X223647Y1343905D03*
X227007Y1372165D03*
Y1382165D03*
X224780Y1443402D03*
X223590Y1635840D03*
X220142Y1640209D03*
X214120Y1713462D03*
X235701Y21582D03*
X241310Y20322D03*
X238063Y26232D03*
X239820Y54362D03*
X239720Y71862D03*
X239010Y78542D03*
X242215Y151788D03*
X230359Y461683D03*
X236267Y763585D03*
X237667Y1027975D03*
X239657Y1035555D03*
X233970Y1245182D03*
X240240Y1252562D03*
X230084Y1251546D03*
X232820Y1259352D03*
X233158Y1441976D03*
X246510Y20362D03*
X246360Y26852D03*
X253910Y115722D03*
X249735Y152694D03*
X259933Y141122D03*
X245490Y159702D03*
X255810Y405582D03*
X252500Y415862D03*
X258066Y426735D03*
X259845Y461117D03*
X257750Y450842D03*
X259510Y757822D03*
X254160Y959342D03*
X254520Y953922D03*
X248575Y988405D03*
X247667Y1027975D03*
X255530Y1057940D03*
X248047Y1261902D03*
X247973Y1249200D03*
X246867Y1632667D03*
X254625Y1632354D03*
X263240Y38122D03*
X266990Y41832D03*
X275120Y28562D03*
X275900Y48872D03*
X263320Y87662D03*
X273620Y96662D03*
X263550Y120922D03*
X269191Y121092D03*
X275797Y120245D03*
X265910Y125492D03*
X260600Y151062D03*
X264578Y159203D03*
X263430Y422235D03*
X262963Y443735D03*
X272500Y447735D03*
X263040Y448752D03*
X272500Y452862D03*
X268331Y738029D03*
X271057Y762425D03*
X273737Y779755D03*
X263747Y885135D03*
X269117Y881535D03*
X276147Y916225D03*
X269977Y965105D03*
X266486Y1038775D03*
X262170Y1255061D03*
X263790Y1248688D03*
X269427Y1381893D03*
X287000Y20862D03*
X290799Y28362D03*
X289400Y54222D03*
X287000Y139862D03*
X276825Y140462D03*
X290685Y165447D03*
X289137Y735275D03*
X288901Y774093D03*
X291215Y782792D03*
X284223Y784922D03*
X289797Y791505D03*
X282417Y880465D03*
X279217Y902685D03*
X289404Y1017414D03*
X281759Y1010061D03*
X291497Y1023995D03*
X276582Y1040899D03*
X284103Y1037625D03*
X289406Y1049524D03*
X290654Y1037501D03*
X287875Y1044423D03*
X299500Y22862D03*
X295520Y26362D03*
X300248Y28362D03*
X302720Y38182D03*
X293161Y50522D03*
X298550Y51602D03*
X303715Y50857D03*
X305247Y71567D03*
X301600Y82457D03*
X302310Y75673D03*
X295357Y88903D03*
X307820Y95724D03*
X305025Y144202D03*
X299628Y149203D03*
Y158703D03*
X295685Y165447D03*
X300520Y552262D03*
X307987Y577658D03*
X293805Y565997D03*
X298000Y587890D03*
X308417Y585158D03*
X308447Y592255D03*
X306144Y602225D03*
X297024Y603533D03*
X296664Y616633D03*
X294679Y685046D03*
X299900Y700962D03*
X306579Y740759D03*
X298197Y786070D03*
X308557Y793945D03*
X307030Y807499D03*
X303730Y887208D03*
X296604Y1029634D03*
X294343Y1044589D03*
X310400Y50362D03*
X323040Y73122D03*
X322875Y84318D03*
X316364Y89212D03*
X310459Y75892D03*
X320430Y78002D03*
X324733Y148598D03*
X309756Y177449D03*
X320270Y200462D03*
X323314Y210645D03*
X322658Y229254D03*
X319718Y223750D03*
X316444Y559125D03*
X317860Y572322D03*
X319520Y577658D03*
X312007Y588675D03*
X319520Y582658D03*
X316127Y592785D03*
X318560Y587632D03*
X311820Y598762D03*
X317386Y623207D03*
X310847Y716105D03*
X317967Y771875D03*
X311417Y782375D03*
X323576Y804265D03*
X315274Y803537D03*
X310049Y813653D03*
X316354Y812166D03*
X310694Y897810D03*
X313886Y904524D03*
X310482Y909310D03*
X325182Y978814D03*
X317202Y970250D03*
X310839Y1023569D03*
X316808Y1033357D03*
X321078Y1038165D03*
X324515Y1060974D03*
X319515D03*
X321739Y1056828D03*
X311117Y1323175D03*
X323247Y1320875D03*
X311117Y1333175D03*
X310608Y1361189D03*
X335575Y214170D03*
X328588Y209677D03*
X328939Y229139D03*
X335385Y235309D03*
X335412Y222176D03*
X341295Y290239D03*
X336270Y402992D03*
X329050Y607402D03*
X331839Y789287D03*
X335473Y782485D03*
X326097Y796665D03*
X341584Y832077D03*
X333877Y869405D03*
X330963Y887959D03*
X326277Y919725D03*
X329807Y968595D03*
Y958595D03*
X327617Y1017035D03*
X341027Y1048921D03*
X325637Y1040899D03*
X327108Y1056694D03*
X336727Y1063055D03*
X330667Y1064105D03*
X331693Y1087864D03*
X325693D03*
X343040Y122522D03*
X343450Y131167D03*
X355189Y144267D03*
X351100Y150412D03*
X356295Y219362D03*
X353145Y228362D03*
X354145Y290591D03*
X343354Y391643D03*
X351422Y700972D03*
X348730Y735098D03*
X344377Y785725D03*
X349637Y986855D03*
X342231Y1055058D03*
X342289Y1338168D03*
X366775Y127662D03*
X366675Y158702D03*
X364014Y366391D03*
X371370Y373622D03*
X364014Y378649D03*
X370200Y409582D03*
X373720Y431362D03*
X365720Y440562D03*
X359639Y690114D03*
X363101Y693948D03*
X360990Y726862D03*
X358902Y739755D03*
X365547Y787015D03*
X363359Y797204D03*
X368830Y792479D03*
X359637Y986855D03*
X380930Y122022D03*
X379295Y131002D03*
X385720Y320902D03*
X376500Y366391D03*
Y378649D03*
X376770Y387272D03*
X390220Y392062D03*
X389920Y461362D03*
X387500Y495362D03*
X389020Y522862D03*
X374590Y736928D03*
X377987Y1297695D03*
X375030Y1325211D03*
X386827Y1429525D03*
X374900Y1534102D03*
X375430Y1676462D03*
X399240Y62722D03*
X404910Y62562D03*
X396294Y281585D03*
X395520Y448362D03*
X402500Y495362D03*
X394500Y522862D03*
X400589Y575236D03*
X399756Y813625D03*
X393156D03*
X399756Y807025D03*
X393156D03*
X406356Y813625D03*
Y807025D03*
X400888Y1395508D03*
X392947Y1397827D03*
X400924Y1408227D03*
X405946Y1408955D03*
X390777Y1435152D03*
X396946Y1537632D03*
X404920Y1539362D03*
X394360Y1616380D03*
X396824Y1673662D03*
X413459Y129061D03*
X420752Y239562D03*
X412720Y439362D03*
X417880Y461942D03*
X418520Y473562D03*
X412956Y813625D03*
Y807025D03*
X408339Y1325927D03*
X418320Y1383862D03*
X410933Y1384648D03*
X414909Y1395658D03*
X408915Y1402606D03*
X411150Y1408163D03*
X415856Y1420283D03*
X416926Y1426471D03*
X412416Y1431645D03*
X419302Y1434700D03*
X410074Y1424993D03*
X413599Y1441908D03*
X409140Y1566892D03*
X416020Y1620862D03*
X412456Y1649838D03*
X417960Y1650072D03*
X422650Y1653040D03*
X421320Y1671699D03*
X410249Y1673082D03*
X427120Y59862D03*
X428500Y65016D03*
Y70016D03*
X435340Y125346D03*
X429780Y153477D03*
X429395Y236562D03*
X428720Y439362D03*
X437720Y435362D03*
X437520Y476337D03*
X431220Y496362D03*
Y507143D03*
Y512623D03*
Y501643D03*
X425550Y924546D03*
X439104Y1324785D03*
X426320Y1383862D03*
X439030Y1383692D03*
X436467Y1391687D03*
X438458Y1402169D03*
X435570Y1398366D03*
X438645Y1426890D03*
X437299Y1436774D03*
X425030Y1434292D03*
X424820Y1552605D03*
X431620Y1541362D03*
X433350Y1579509D03*
X432200Y1607060D03*
X432500Y1613822D03*
X435500Y1646962D03*
X446640Y104552D03*
X443678Y145710D03*
X446746Y152662D03*
X442220Y323362D03*
X448220Y323582D03*
X450500Y358862D03*
X446730Y382432D03*
X443770Y371042D03*
X443300Y410962D03*
X447750Y414112D03*
X453020Y414262D03*
X443744Y429553D03*
X451421D03*
X442520Y476337D03*
Y484837D03*
X451520D03*
X453680Y515072D03*
X439427Y793255D03*
X449427D03*
X441836Y841835D03*
X448436D03*
X443842Y1389106D03*
X448020Y1391862D03*
X443424Y1397869D03*
X441369Y1394260D03*
X442970Y1406832D03*
X453805Y1396730D03*
X448114Y1396812D03*
X445230Y1411719D03*
X445723Y1419730D03*
X449778Y1441606D03*
X452520Y1564862D03*
X454661Y1609235D03*
X448181Y1614401D03*
X443800Y1610712D03*
X444940Y1641842D03*
X462320Y115948D03*
X466992Y145888D03*
X458264Y254862D03*
X461736Y306098D03*
X469830Y366158D03*
X456660Y359172D03*
X460800Y375362D03*
X455720Y404762D03*
X458600Y414262D03*
X466520Y475812D03*
X461520Y484837D03*
X457456Y522516D03*
X470880Y572692D03*
X467130Y600122D03*
X469427Y793255D03*
X459427D03*
X467436Y925602D03*
X456327Y926551D03*
X471437Y1294035D03*
X471545Y1325025D03*
X459321Y1396409D03*
X458441Y1414893D03*
X468880Y1418400D03*
X467400Y1556700D03*
X466520Y1574862D03*
X457220Y1603562D03*
X455681Y1622492D03*
X458978Y1634481D03*
X463344Y1637622D03*
X469580Y1640272D03*
X466460Y1672332D03*
X466180Y1678392D03*
X484396Y161364D03*
X476220Y158772D03*
X486720Y360862D03*
X482920Y398060D03*
X485020Y414162D03*
X480393Y429412D03*
X471920Y416687D03*
X474169Y476196D03*
X479169D03*
X482780Y607012D03*
X479427Y793255D03*
X474703Y925819D03*
X480587Y1294035D03*
X477968Y1548122D03*
X486210Y1547960D03*
X482400Y1558320D03*
X477905Y1659242D03*
X475150Y1654302D03*
X494112Y88040D03*
X503310Y113262D03*
X497800Y113562D03*
X500500Y117962D03*
X492150Y336810D03*
X498720Y360862D03*
X497568Y397632D03*
X489520Y411862D03*
X494020Y414262D03*
X502070Y424787D03*
X488070Y429412D03*
X493169Y476196D03*
X498169D03*
X493169Y484696D03*
X503218Y1337798D03*
X490307Y1421499D03*
X488920Y1408742D03*
X507335Y88862D03*
X510600Y92782D03*
X504700Y93862D03*
X513700Y117862D03*
X510900Y111962D03*
X519010Y147912D03*
X518186Y139821D03*
X514850Y168443D03*
X519236Y202404D03*
X518670Y219192D03*
X507160Y332452D03*
X514720Y360862D03*
X513720Y390362D03*
X513173Y408740D03*
X514637Y1426345D03*
X505777Y1425579D03*
X529720Y43054D03*
X534720Y42922D03*
X523978Y59074D03*
X529078Y59282D03*
X523220Y170362D03*
X534765Y161067D03*
X526920Y161362D03*
X529480Y183921D03*
X536127Y247652D03*
X531298Y284280D03*
X526980Y322582D03*
X521820Y336762D03*
X531720Y360862D03*
X535220Y383552D03*
X525720Y390362D03*
X528145Y408705D03*
X526941Y447802D03*
X532650Y442376D03*
Y450330D03*
Y454270D03*
X536000Y520362D03*
X524820Y545319D03*
X533167Y1329625D03*
Y1337025D03*
X528975Y1369724D03*
X535339Y1361318D03*
X533826Y1423065D03*
X524317Y1420335D03*
X542050Y47452D03*
X539720Y42862D03*
X550971Y42902D03*
X544720Y42892D03*
X548609Y48082D03*
X546100Y106162D03*
X546110Y100647D03*
X548942Y97821D03*
X544700Y112362D03*
X543083Y146338D03*
X548390Y236512D03*
X546390Y231742D03*
X539830Y274912D03*
X549220Y339687D03*
X546758Y360502D03*
X550024Y369123D03*
Y401023D03*
X551046Y878964D03*
X549757Y894025D03*
X545778Y948495D03*
X541378Y951944D03*
X541477Y976940D03*
X549177Y1010925D03*
X538209Y1027241D03*
X539914Y1049923D03*
X545371Y1041871D03*
X543914Y1049923D03*
X541167Y1329625D03*
Y1337025D03*
X549167D03*
Y1329625D03*
X542867Y1420245D03*
X565184Y47982D03*
X553650Y48842D03*
X562500Y104962D03*
X562300Y109962D03*
X562200Y114962D03*
X558900Y118962D03*
X564890Y142173D03*
X555220Y167937D03*
X561324Y301149D03*
X555520Y309827D03*
X557701Y369123D03*
X569080Y414002D03*
X559300Y422732D03*
X563700Y538477D03*
X566762Y882180D03*
X557947Y882255D03*
X558697Y891555D03*
X556697Y943475D03*
X565937Y968755D03*
X553332Y1026465D03*
X562700Y1022464D03*
X561157Y1029735D03*
X567343Y1041819D03*
X556151Y1037465D03*
X565849Y1346968D03*
X566510Y1352217D03*
X573190Y42912D03*
X575330Y47672D03*
X570208Y47982D03*
X579930Y72052D03*
X578900Y60362D03*
X573360Y140532D03*
X581175Y164717D03*
X569965Y161232D03*
X569470Y171702D03*
X579481Y194378D03*
X578450Y218562D03*
X578390Y225362D03*
X577676Y300268D03*
X570440Y331930D03*
X571830Y348772D03*
X570200Y372229D03*
X571720Y381862D03*
X577720D03*
X574491Y376549D03*
X581090Y426970D03*
X571930Y421232D03*
X571110Y442656D03*
Y446706D03*
X577220Y449462D03*
X583220Y493212D03*
X584173Y498422D03*
X577470Y505592D03*
X581147Y880067D03*
X575374Y889216D03*
X577622Y896854D03*
X583377Y901635D03*
X570657Y903335D03*
X580302Y908535D03*
X574007Y911355D03*
X570067Y921425D03*
X579229Y964343D03*
X580027Y1039100D03*
X586260Y52222D03*
X599800Y43152D03*
X597955Y48047D03*
X593369Y45682D03*
X590680Y83591D03*
X598295Y171862D03*
X599720Y184887D03*
X593220D03*
X595415Y246515D03*
X593763Y293999D03*
X588850Y291622D03*
X593120Y342782D03*
X586070Y352302D03*
X591720Y430787D03*
X595380Y416660D03*
X599220Y444362D03*
X597220Y458688D03*
X590210Y484132D03*
X589260Y519421D03*
X598503Y768931D03*
X600406Y882536D03*
X595572Y893190D03*
X600850Y902101D03*
X587617Y895115D03*
X592307Y1031185D03*
X594081Y1042722D03*
X599924Y1058989D03*
X586079Y1055076D03*
X591675Y1056610D03*
X601900Y1079662D03*
X611810Y34400D03*
X615530Y52792D03*
X614400Y46012D03*
X603063Y48023D03*
X606020Y84562D03*
X603720Y98362D03*
X608620Y94162D03*
X617409D03*
X602580Y151052D03*
X603019Y146399D03*
X606260Y161652D03*
X605350Y293092D03*
X605870Y298172D03*
X605560Y303372D03*
X607590Y314732D03*
X614130Y328762D03*
X605305Y331162D03*
X615180Y336812D03*
X605898Y372984D03*
X609690Y402812D03*
X604779Y423862D03*
X604360Y452120D03*
X609520Y515162D03*
X613220Y654662D03*
X603276Y741375D03*
X602768Y758385D03*
X608709Y769103D03*
X605555Y779324D03*
X603592Y1045812D03*
X609954Y1047613D03*
X614678Y1050637D03*
X605050Y1065867D03*
X612317Y1068895D03*
X626490Y51572D03*
X624860Y56712D03*
X625000Y43952D03*
X623300Y95762D03*
X620540Y100112D03*
X632300Y104472D03*
X627645Y236862D03*
X622730Y230362D03*
X629564Y256277D03*
X633150Y301457D03*
X627950Y298897D03*
X627600Y309134D03*
X632143Y306575D03*
X619474Y331162D03*
X622490Y402162D03*
X623220Y426362D03*
X625620Y447862D03*
Y442862D03*
X626400Y462812D03*
X625620Y457862D03*
Y452862D03*
X622860Y487310D03*
X623670Y507862D03*
X633000Y508700D03*
X628070Y760251D03*
X631231Y764219D03*
X632080Y1262074D03*
X626260Y1248762D03*
X628970Y1670880D03*
X643880Y42142D03*
X635800Y45762D03*
X647447Y46322D03*
X641200Y46762D03*
X637000Y68142D03*
X634500Y73422D03*
X645330Y77132D03*
X640220Y85542D03*
X634690D03*
X639901Y103462D03*
X640000Y108542D03*
X639970Y113892D03*
X635600Y151012D03*
X649870Y181942D03*
X645263Y235689D03*
X640295Y234237D03*
X636075Y389862D03*
X649075Y389937D03*
X638700Y400962D03*
X637220Y411362D03*
Y416362D03*
Y426362D03*
X640720Y452862D03*
X641235Y477377D03*
X640620Y483422D03*
X649218Y504277D03*
X642580Y508172D03*
X636960Y516002D03*
X648296Y528255D03*
X640785Y952415D03*
Y959265D03*
X647689Y997251D03*
X647690Y1260812D03*
X637041Y1248685D03*
X642548Y1248785D03*
X649197Y1251276D03*
X643725Y1643467D03*
X648225Y1658482D03*
X642725Y1658562D03*
X635410Y1664220D03*
X637540Y1669480D03*
X645725Y1691182D03*
X640725Y1691452D03*
X650725Y1690682D03*
X642225Y1708457D03*
X648220Y1716912D03*
X636160Y1710662D03*
X648220Y1722921D03*
X651680Y73812D03*
X656500Y69662D03*
X661587D03*
X661600Y75562D03*
X656426Y75431D03*
X652320Y123362D03*
X651730Y177212D03*
X659877Y188372D03*
X659871Y192372D03*
X660490Y200172D03*
X652000Y402362D03*
X653100Y407862D03*
X654780Y422722D03*
X654510Y431362D03*
X659970Y419602D03*
X654300Y447002D03*
X664990Y454252D03*
X655820Y452662D03*
X655800Y461432D03*
X662480Y449782D03*
X662500Y467030D03*
X664140Y475362D03*
X657740Y473132D03*
X665610Y482662D03*
X661865Y505334D03*
X656877Y514716D03*
X665990Y517131D03*
X661220Y526862D03*
X650794Y515039D03*
X664630Y1259442D03*
X664709Y1249918D03*
X661400Y1263522D03*
X651725Y1643397D03*
X677560Y40572D03*
X672250Y40812D03*
X682290Y46822D03*
X674035Y74522D03*
X677820Y89462D03*
X680578Y75992D03*
X674540Y80652D03*
X670800Y85932D03*
X667940Y80142D03*
X671320Y91192D03*
X673720Y110362D03*
X668300Y132400D03*
X673713Y237725D03*
X683100Y369550D03*
X670940Y406452D03*
X681610Y446062D03*
X675220Y508862D03*
X680220D03*
X673340Y530922D03*
X676535Y769812D03*
X670485Y952415D03*
Y959265D03*
X676309Y994386D03*
X678683Y1254408D03*
X672188Y1248885D03*
X677980Y1262074D03*
X672773Y1404136D03*
X682160Y1548040D03*
X678621Y1571072D03*
X678619Y1579070D03*
X673420Y1650057D03*
X671610Y1673792D03*
X675120Y1716242D03*
X672270Y1721612D03*
X687120Y39632D03*
X692289Y40633D03*
X696800Y42108D03*
X696838Y47940D03*
X683440Y42832D03*
X687344Y46940D03*
X692389Y46439D03*
X690027Y70142D03*
X699475Y69982D03*
X688019Y109845D03*
X687034Y115896D03*
X692083Y128157D03*
X697615Y123697D03*
X698900Y135782D03*
X687238Y171071D03*
X690520Y399622D03*
X685220Y391652D03*
X694880Y412255D03*
X693300Y418362D03*
X685220Y495887D03*
X697972Y481734D03*
X695220Y495887D03*
X690220D03*
X695220Y508862D03*
X690330Y503530D03*
X695220Y516852D03*
X699040Y952592D03*
X698920Y959252D03*
X697533Y1252541D03*
X694100Y1261562D03*
X699186Y1246192D03*
X692233Y1252480D03*
X696810Y1300162D03*
X692280Y1302532D03*
X692100Y1567190D03*
X686220Y1640667D03*
X697595Y1666862D03*
X701838Y42202D03*
Y47940D03*
X712340Y128093D03*
X707008Y125804D03*
X715600Y363900D03*
X705700Y361400D03*
X711200Y396500D03*
X713220Y388362D03*
X707330Y406232D03*
X712781Y420381D03*
X702940Y486652D03*
X701757Y521324D03*
X711220Y516852D03*
X705220Y530362D03*
X710417Y773685D03*
X701087Y988721D03*
X708090Y1262074D03*
X703790Y1249622D03*
X709748Y1252004D03*
X708126Y1403331D03*
X712222Y1570703D03*
X711102Y1575683D03*
X712582Y1584843D03*
X715775Y1599024D03*
X706103Y1617107D03*
X708857Y1613462D03*
X710570Y1629890D03*
X708830Y1623115D03*
X708999Y1646762D03*
X703719Y1646768D03*
X700460Y1660918D03*
X709678Y1658485D03*
X704759Y1677001D03*
X724620Y40062D03*
X728720Y43562D03*
X719820Y45862D03*
X729933Y108388D03*
X722500Y365500D03*
X727000D03*
X731400D03*
X725220Y380787D03*
X722500Y374100D03*
X727000D03*
X731400Y375000D03*
X728220Y388362D03*
X725280Y406242D03*
X721873Y421132D03*
X723220Y508882D03*
X717220D03*
X729220D03*
X729212Y531700D03*
X720240Y598292D03*
X729885Y952415D03*
Y959265D03*
X723975Y984675D03*
X723037Y1045285D03*
X731467Y1045015D03*
X723850Y1235892D03*
X723700Y1258727D03*
X722792Y1248688D03*
X728977Y1574453D03*
X717402Y1574433D03*
X723942Y1574123D03*
X729052Y1602518D03*
X726092Y1598483D03*
X720987Y1599568D03*
X718758Y1673800D03*
X745900Y40362D03*
X733314Y40862D03*
X740100Y41162D03*
X746100Y46262D03*
X736620Y45262D03*
X742960Y76142D03*
X733879Y83664D03*
X737929Y83714D03*
X736720Y101662D03*
X745035Y94632D03*
X735770Y94988D03*
X739823Y91052D03*
X741308Y108742D03*
X740220Y145362D03*
X732720Y231362D03*
X745685Y269322D03*
X741800Y363200D03*
X735800Y365500D03*
X732700Y351500D03*
X740200Y375100D03*
X735800Y375000D03*
X733220Y388362D03*
X733590Y406242D03*
X742450Y431472D03*
X738670Y417482D03*
X743980Y443482D03*
X742360Y436662D03*
X740510Y465258D03*
X741420Y494162D03*
X745700Y492062D03*
X747600Y506592D03*
X735220Y508862D03*
X745220Y522362D03*
X735173Y521362D03*
X740909Y754975D03*
X736425Y770072D03*
X738638Y1253541D03*
X737580Y1262074D03*
X740840Y1655590D03*
X750700Y106642D03*
X754800Y97082D03*
X757340Y92562D03*
X762590Y274028D03*
X758412Y298790D03*
X758390Y307272D03*
X749650Y398532D03*
X748380Y429052D03*
X757365Y459862D03*
X752500Y495762D03*
X757238Y483862D03*
X751220Y522362D03*
X755940Y516862D03*
X756650Y526072D03*
X761710Y517651D03*
X762570Y756052D03*
X751997Y952481D03*
Y959331D03*
X751505Y987865D03*
X751957Y1041755D03*
X759237Y1253019D03*
X753000Y1261352D03*
X759149Y1247626D03*
X753656Y1250281D03*
X748630Y1251792D03*
X751927Y1301285D03*
X757720Y1375462D03*
Y1384062D03*
X758020Y1397862D03*
X758420Y1406862D03*
X758120Y1414762D03*
X749612Y1579023D03*
X749652Y1586407D03*
X749612Y1594683D03*
X758360Y1589661D03*
X750504Y1612521D03*
X758830Y1674823D03*
X751620Y1674312D03*
X763994Y1674691D03*
X774059Y68912D03*
X764850Y249792D03*
X766320Y264892D03*
X768490Y354942D03*
X774490D03*
X773245Y398212D03*
Y403212D03*
Y408212D03*
X771050Y416940D03*
X766195Y428212D03*
X772365Y454862D03*
Y459862D03*
X765810Y506342D03*
X769745Y502600D03*
X775378Y502502D03*
X766125Y770072D03*
X767080Y1262074D03*
X767053Y1251480D03*
X776922Y1590444D03*
X766811Y1661726D03*
X766603Y1721797D03*
X790120Y135412D03*
X795520Y393462D03*
X781320Y398212D03*
X787320Y444862D03*
Y439862D03*
Y454862D03*
Y449862D03*
Y459862D03*
X787360Y469862D03*
X796315Y469290D03*
X783340Y474802D03*
X782690Y488862D03*
X785800Y482762D03*
X783600Y502462D03*
X783450Y522462D03*
X791969Y618384D03*
X794658Y770104D03*
X789385Y952415D03*
Y959265D03*
X789877Y987865D03*
X783130Y1259372D03*
X794157Y1248685D03*
X788890Y1248688D03*
X796880Y1262074D03*
X796280Y1254402D03*
X797052Y1611893D03*
X801840Y276587D03*
X802070Y284092D03*
X805775Y297007D03*
X805570Y307622D03*
X802220Y393727D03*
X800352Y408389D03*
X803120Y428762D03*
X797720Y428412D03*
X798370Y439932D03*
X802790Y433832D03*
X801750Y444330D03*
X802810Y454862D03*
Y464862D03*
Y449862D03*
Y459862D03*
X802865Y474862D03*
X810815D03*
X812510Y486422D03*
X801567Y512942D03*
X810850Y770272D03*
X812440Y1258727D03*
X801935Y1252215D03*
X811521Y1248688D03*
X806323Y1343076D03*
X812130Y1343022D03*
X812652Y1577793D03*
X801652Y1584539D03*
X814570Y145952D03*
X814531Y139851D03*
X820900Y147112D03*
X825003Y389012D03*
X819220Y412264D03*
X821720Y428437D03*
X816810Y464862D03*
X816400Y472900D03*
X821720Y511082D03*
Y527082D03*
X815650Y516807D03*
X826497Y739255D03*
X826930Y752352D03*
X825425Y770072D03*
X819085Y952415D03*
Y959265D03*
X819577Y987865D03*
X826750Y1262074D03*
X824268Y1256206D03*
X825256Y1249197D03*
X836779Y68008D03*
X839898Y87248D03*
X841584Y94181D03*
X845220Y135862D03*
Y129362D03*
X837160Y218212D03*
Y213207D03*
X844526Y204968D03*
X838820Y206872D03*
X844250Y301629D03*
X844100Y309306D03*
X838784Y392880D03*
X838220Y459562D03*
X838645Y492862D03*
X832590Y512888D03*
X829745Y498082D03*
X834327Y769285D03*
X840851Y1229802D03*
X845240Y1242372D03*
X842630Y1256912D03*
X841747Y1246745D03*
X832090Y1326862D03*
X839052Y1611893D03*
X850015Y87341D03*
X847472Y94754D03*
X860050Y215310D03*
X847580Y232222D03*
X861865Y273730D03*
X856243Y286447D03*
X859920Y308852D03*
X859740Y399081D03*
X856842Y410760D03*
X846490Y422131D03*
X857560Y417762D03*
X850610Y444352D03*
X857620Y492862D03*
X848620Y509752D03*
X853070Y515447D03*
X860345Y522162D03*
X848685Y952415D03*
Y959265D03*
X849177Y987865D03*
X851867Y1256798D03*
X875169Y185113D03*
X873200Y194262D03*
X877971Y196652D03*
X867528Y231788D03*
X867700Y268262D03*
X863747Y280870D03*
X867237Y273325D03*
X868552Y285537D03*
X868113Y409372D03*
X862320Y431462D03*
X863415Y445829D03*
X868110Y499142D03*
X866820Y736562D03*
X883909Y281862D03*
X879587Y270004D03*
X883870Y272652D03*
X887338Y296760D03*
X893440Y336232D03*
X890820Y389362D03*
X887810Y582442D03*
X885310Y736442D03*
X884619Y916477D03*
X892317Y915872D03*
X888652Y1597793D03*
Y1609793D03*
X896540Y341132D03*
X900490Y482752D03*
X899049Y501792D03*
X896652Y1605793D03*
X922726Y176302D03*
X922100Y181791D03*
X917386Y184114D03*
X923836Y193563D03*
X927034Y445594D03*
X914300Y486862D03*
X911361Y508201D03*
X920070Y966320D03*
X917980Y974952D03*
X914838Y985989D03*
X926120Y1671500D03*
X914500Y1671400D03*
X940424Y184190D03*
X936424D03*
X940410Y188852D03*
X931580Y472092D03*
X937000Y489179D03*
X935052Y812630D03*
X927790Y966450D03*
X939740Y987762D03*
X933700Y1671500D03*
X957020Y264862D03*
X947100Y374462D03*
X946300Y392562D03*
X950660Y399472D03*
X949920Y404602D03*
X945100Y534464D03*
X957220Y582862D03*
X949560Y981392D03*
X946100Y1671800D03*
X962570Y282812D03*
X962882Y314512D03*
X963854Y320113D03*
X974026Y398056D03*
X975670Y392063D03*
X971600Y408602D03*
X963720Y439862D03*
X969351Y512416D03*
X965904Y1554364D03*
X960904D03*
X962086Y1603984D03*
X990501Y152397D03*
X986369Y155358D03*
X985499Y168753D03*
X990115Y173039D03*
X987259Y276094D03*
X978000Y362462D03*
X988723Y369650D03*
X986400Y383123D03*
X983770Y373962D03*
X979766Y377507D03*
X977949Y384205D03*
X980856Y392502D03*
X983629Y397628D03*
X991369Y408252D03*
X979240Y425212D03*
X989635Y426655D03*
X980720Y512362D03*
X992306Y1295049D03*
X984270Y1554364D03*
X995180Y153689D03*
X1001101Y165510D03*
X996415Y172579D03*
X1002920Y174799D03*
X1008120Y198293D03*
X1000610Y211039D03*
X1005640Y210969D03*
X994743Y289843D03*
X993901Y376544D03*
X1006201Y370004D03*
X999440Y371782D03*
X996922Y367764D03*
X1005123Y414662D03*
X997617Y412383D03*
X997225Y419162D03*
X1005720Y498862D03*
X1005520Y510932D03*
X1008560Y589682D03*
X1007444Y766798D03*
X1001970Y1251522D03*
X1002070Y1256942D03*
X1006897Y1262435D03*
X1007636Y1554364D03*
X993698Y1604000D03*
X1011320Y202169D03*
X1017360Y199109D03*
X1019355Y218423D03*
X1010005Y208424D03*
X1010470Y224169D03*
X1022957Y249528D03*
X1024720Y259662D03*
X1017547Y255928D03*
X1014500Y266862D03*
X1021118Y294290D03*
X1015520Y302862D03*
X1009800Y343800D03*
X1009883Y367955D03*
X1010420Y416062D03*
X1019300Y405662D03*
X1024200Y510362D03*
X1020392Y521826D03*
X1016360Y594682D03*
X1019000Y601042D03*
X1021654Y606302D03*
X1023203Y989083D03*
X1023012Y1245659D03*
X1015170Y1249722D03*
X1022835Y1252034D03*
X1032547Y247928D03*
Y255928D03*
X1037618Y261200D03*
X1025862Y291727D03*
X1032260Y294532D03*
X1036278Y307393D03*
X1026250Y381582D03*
X1039340Y372642D03*
X1025004Y374662D03*
X1031153Y390152D03*
X1039370Y413842D03*
Y418842D03*
X1038294Y506504D03*
X1032155Y509737D03*
X1025530Y519627D03*
X1033040Y519852D03*
X1038130Y518417D03*
X1040720Y591862D03*
X1029630Y601252D03*
X1037144Y766798D03*
X1032063Y950820D03*
X1032527Y959265D03*
X1030830Y1261302D03*
X1030270Y1256042D03*
X1031002Y1554364D03*
X1025298Y1604000D03*
X1044978Y267275D03*
Y275275D03*
X1043720Y363462D03*
X1047010Y1259222D03*
X1057047Y1256865D03*
X1055531Y1248688D03*
X1044930Y1263492D03*
X1054368Y1554364D03*
X1056898Y1604000D03*
X1059978Y267275D03*
Y283275D03*
Y275275D03*
X1072310Y364422D03*
X1062120Y477462D03*
X1058220Y585862D03*
X1061867Y774038D03*
X1062123Y950460D03*
X1062227Y959265D03*
X1061837Y994357D03*
X1061330Y1262074D03*
X1059410Y1252272D03*
X1059086Y1579240D03*
X1085300Y282162D03*
X1077270Y374131D03*
X1076598Y477087D03*
X1081930Y477132D03*
X1076739Y506461D03*
X1077751Y522235D03*
X1084376Y774754D03*
X1084239Y952481D03*
X1084703Y960926D03*
X1079367Y984535D03*
X1084140Y1245202D03*
X1076520Y1259072D03*
X1086613Y1256826D03*
X1074010Y1510650D03*
X1077734Y1554364D03*
X1105580Y132822D03*
X1100630Y130376D03*
X1105553Y356475D03*
X1095199Y768537D03*
X1097749Y779005D03*
X1093172Y1011260D03*
X1104601Y1244631D03*
X1091000Y1262074D03*
X1106200Y1250162D03*
X1103530Y1263602D03*
X1105480Y1517982D03*
X1101600Y1554364D03*
X1104750Y1549346D03*
X1103960Y1576300D03*
Y1583300D03*
Y1590300D03*
X1092436Y1603944D03*
X1118486Y208942D03*
X1111918Y234718D03*
X1120190Y255652D03*
X1121523Y950460D03*
X1121627Y959265D03*
X1121237Y994357D03*
X1114448Y1245353D03*
X1120920Y1246282D03*
X1120800Y1262074D03*
X1106740Y1267902D03*
X1110725Y1518046D03*
X1115802Y1615010D03*
X1117182Y1625460D03*
X1114150Y1715726D03*
X1132547Y64864D03*
X1129997Y69864D03*
X1128485Y198159D03*
X1124360Y259712D03*
X1125409Y305797D03*
X1124120Y643762D03*
X1136720Y641362D03*
X1125194Y768709D03*
X1131721Y1439984D03*
X1127377Y1628485D03*
X1147700Y362731D03*
X1140465Y379592D03*
X1147700Y368041D03*
X1140912Y602207D03*
X1152241Y766798D03*
X1151223Y950460D03*
X1151327Y959265D03*
X1140727Y985255D03*
X1144577Y1244341D03*
X1139796Y1248338D03*
X1144792Y1249984D03*
X1150400Y1262074D03*
X1148563Y1257097D03*
X1152397Y1301095D03*
X1153465Y1550301D03*
X1140750Y1604330D03*
X1139392Y1620851D03*
X1159460Y194090D03*
X1159753Y361281D03*
X1156790Y373231D03*
X1157980Y588892D03*
X1158020Y593812D03*
X1158030Y598952D03*
X1158047Y609052D03*
X1158054Y603965D03*
X1159078Y763401D03*
X1158997Y1301095D03*
X1165597D03*
X1170670Y1439635D03*
X1163308Y1524187D03*
X1155433D03*
X1169213Y1550301D03*
X1161339D03*
X1169460Y1606630D03*
Y1616630D03*
Y1611630D03*
X1164830Y1628830D03*
Y1645632D03*
X1169325Y1642600D03*
X1158325D03*
X1162383Y1652505D03*
X1161613Y1669112D03*
X1187413Y143132D03*
X1181420Y157962D03*
X1181700Y186962D03*
X1173314Y176452D03*
X1181470Y208802D03*
X1181500Y222162D03*
X1172795Y222174D03*
X1186653Y302242D03*
X1174120Y355362D03*
X1180923Y950460D03*
X1181027Y959265D03*
X1180637Y994357D03*
X1179080Y1260672D03*
X1174331Y1248688D03*
X1177222Y1255567D03*
X1179180Y1265872D03*
X1172197Y1301095D03*
X1184200Y1599900D03*
X1185030Y1624660D03*
X1186830Y1645632D03*
X1175830D03*
X1180325Y1642600D03*
X1173383Y1652505D03*
X1184383D03*
X1183613Y1669112D03*
X1172613D03*
X1193532Y132644D03*
X1196930Y126690D03*
X1194800Y143112D03*
X1197414Y161592D03*
X1191020Y170862D03*
X1194840Y240672D03*
X1192877Y595012D03*
X1201977Y593252D03*
X1197280Y610352D03*
X1192890Y600292D03*
X1192887Y605652D03*
X1202495Y961858D03*
X1201627Y955185D03*
X1201403Y989083D03*
X1195097Y1251575D03*
X1193590Y1267912D03*
X1195470Y1262802D03*
X1194842Y1373682D03*
X1194442Y1380612D03*
X1203832Y1409772D03*
Y1419772D03*
X1187830Y1522188D03*
X1198546Y1524688D03*
X1187720Y1536362D03*
X1198485Y1534313D03*
X1187720Y1553692D03*
Y1544292D03*
X1198436Y1551192D03*
Y1561062D03*
X1187720Y1563182D03*
X1201600Y1633790D03*
X1197400Y1645942D03*
X1190895Y1642910D03*
X1194183Y1669422D03*
X1197240Y1691422D03*
X1190735Y1688390D03*
X1194793Y1698295D03*
X1201505Y1688435D03*
X1194023Y1714902D03*
X1215763Y114363D03*
X1206114Y132962D03*
X1206694Y139512D03*
X1213420Y144962D03*
X1214415Y153962D03*
X1214054Y186092D03*
X1208518Y174162D03*
X1213720Y195362D03*
X1215720Y204862D03*
X1219060Y213312D03*
X1206660Y224742D03*
X1213540Y224792D03*
X1207220Y247148D03*
X1210900Y265300D03*
X1205165Y380962D03*
X1218870Y418082D03*
X1214000Y599262D03*
X1208980Y598462D03*
X1212407Y773625D03*
X1209457Y787702D03*
X1204161Y1244598D03*
X1209790Y1259423D03*
X1204305Y1254514D03*
X1208750Y1266546D03*
X1210457Y1658415D03*
X1205820Y1652910D03*
X1213980Y1676500D03*
X1217210Y1684520D03*
X1218810Y1691732D03*
X1208010Y1691467D03*
X1212305Y1688700D03*
X1216363Y1698605D03*
X1205563Y1698340D03*
X1215593Y1715212D03*
X1204793Y1714947D03*
X1225100Y91500D03*
X1223500Y111162D03*
X1229500Y125100D03*
X1225574Y188662D03*
X1225320Y200162D03*
X1233780Y214572D03*
X1232000Y248332D03*
X1230720Y380362D03*
X1224300Y380400D03*
X1224439Y956561D03*
X1231327Y955185D03*
X1224031Y988295D03*
X1232107Y1057940D03*
X1228500Y1242102D03*
X1235234Y1256802D03*
X1224007Y1251715D03*
X1244200Y112862D03*
X1249362Y111600D03*
X1237664Y141202D03*
X1249430Y147620D03*
X1241100Y145842D03*
X1246272Y164889D03*
X1243100Y160181D03*
X1249720Y177662D03*
X1242470Y173612D03*
X1243184Y182422D03*
X1248868Y213414D03*
X1246853Y208229D03*
X1245593Y237462D03*
X1240500Y244332D03*
X1252040Y306480D03*
X1246079Y876083D03*
X1251727Y907485D03*
X1244237Y928847D03*
X1250230Y933374D03*
X1244383Y939465D03*
X1247301Y1022801D03*
X1247044Y1065220D03*
X1248000Y1089723D03*
X1239435Y1248688D03*
X1246654Y1660152D03*
X1267014Y112012D03*
X1266926Y118057D03*
X1254520Y115562D03*
X1253161Y128848D03*
X1256093Y149462D03*
X1265010Y162222D03*
X1261899Y174648D03*
X1263830Y195682D03*
X1252720Y193362D03*
X1267315Y220701D03*
X1252930Y205462D03*
X1259703Y209808D03*
X1253440Y230552D03*
X1253860Y235622D03*
X1253950Y246692D03*
X1266715Y244692D03*
X1254370Y241302D03*
X1265065Y249982D03*
X1258250Y292986D03*
X1263150Y294726D03*
X1267150Y305998D03*
X1256220Y434362D03*
X1261220Y454362D03*
X1253220Y451362D03*
X1267220D03*
X1255920Y511362D03*
X1261607Y853715D03*
X1265003Y860128D03*
X1254788Y873600D03*
X1262954Y873559D03*
X1258891Y881517D03*
X1264570Y891259D03*
X1256097Y914995D03*
X1267447Y912265D03*
X1252880Y924465D03*
X1260887Y935665D03*
X1254166Y942501D03*
X1253087Y978815D03*
X1260502Y1015250D03*
X1264362Y1048399D03*
X1267471Y1060464D03*
X1253916Y1051209D03*
X1253863Y1071764D03*
X1265784Y1076853D03*
X1260341Y1067280D03*
X1259335Y1074313D03*
X1265387Y1083345D03*
X1253557Y1086495D03*
X1257586Y1334649D03*
X1259433Y1660486D03*
X1275820Y87962D03*
X1269420Y96012D03*
X1271284Y108971D03*
X1278949Y123567D03*
X1282764Y135398D03*
X1269228Y147097D03*
X1277820Y140682D03*
X1281093Y144516D03*
X1277490Y165946D03*
X1271954Y159143D03*
X1271593Y165962D03*
X1276952Y174834D03*
X1278093Y184462D03*
X1278183Y201262D03*
X1272893Y191262D03*
X1271315Y220701D03*
X1284383Y215762D03*
X1284746Y207271D03*
X1277355Y216851D03*
X1273093Y213962D03*
X1280134Y235206D03*
X1277749Y230871D03*
X1277661Y225685D03*
X1278783Y221386D03*
X1282654Y226309D03*
X1276800Y276562D03*
X1269960Y294536D03*
X1272530Y429362D03*
X1284220D03*
X1280270Y434362D03*
X1272220D03*
X1278380Y463362D03*
X1276220Y477362D03*
X1283220D03*
X1277266Y868490D03*
X1278043Y862242D03*
X1271410Y866886D03*
X1270912Y877372D03*
X1270249Y885331D03*
X1271402Y904801D03*
X1278764Y1015609D03*
X1277461Y1041864D03*
X1284922Y1038464D03*
X1277419Y1062985D03*
X1283822Y1055804D03*
X1275830Y1056275D03*
X1271087Y1093050D03*
X1270528Y1100231D03*
X1275528D03*
X1272550Y1347922D03*
X1269012Y1371693D03*
X1274548Y1660486D03*
X1293454Y81232D03*
X1298640Y93062D03*
X1292880Y93162D03*
X1292899Y98519D03*
X1297884Y120072D03*
X1294751Y133852D03*
X1288093Y125962D03*
X1291478Y137745D03*
X1286150Y131092D03*
X1291311Y152073D03*
X1300481Y151020D03*
X1286513Y161483D03*
X1290734Y199122D03*
X1285899Y196392D03*
X1291194Y188899D03*
X1288904Y204002D03*
X1289739Y218499D03*
X1291983Y208562D03*
X1285393Y222262D03*
X1292554Y230101D03*
X1301235Y228210D03*
X1285710Y249182D03*
X1290293Y247562D03*
X1288637Y240448D03*
X1292630Y240462D03*
X1298032Y267219D03*
X1295540Y440902D03*
X1301310Y440862D03*
X1291220Y463362D03*
X1294440Y477267D03*
X1300220Y477362D03*
X1299327Y765475D03*
X1297298Y790982D03*
X1285316Y865291D03*
X1295535Y871113D03*
X1298830Y864461D03*
X1292792Y928724D03*
X1288257Y921605D03*
X1296637Y970755D03*
X1300851Y1043664D03*
X1296478Y1064139D03*
X1298540Y1056104D03*
X1291775Y1055990D03*
X1288529Y1069460D03*
X1288000Y1362151D03*
X1296930Y1660520D03*
X1311260Y83032D03*
X1314406Y97756D03*
X1308274Y104162D03*
X1310000Y113552D03*
X1302080Y117032D03*
X1302509Y134795D03*
X1308825Y136721D03*
X1315353Y146030D03*
X1310880Y143431D03*
X1315020Y139762D03*
X1305115Y142712D03*
X1309049Y182865D03*
X1309918Y201187D03*
X1314970Y219772D03*
X1306190Y210502D03*
X1309189Y206274D03*
X1316842Y238692D03*
X1317300Y250162D03*
X1316754Y268442D03*
X1317100Y553900D03*
X1303576Y659671D03*
X1305187Y735630D03*
X1304707Y769984D03*
X1307627Y764735D03*
X1314227Y770855D03*
X1301927Y759935D03*
X1305117Y797125D03*
X1311407Y868055D03*
X1307717Y888265D03*
X1311798Y1054354D03*
X1305878Y1062943D03*
X1317150Y1062622D03*
X1316092Y1053513D03*
X1307032Y1058856D03*
X1311780Y1058894D03*
X1311952Y1321945D03*
X1304066Y1323578D03*
X1309194Y1655255D03*
X1313583Y1660466D03*
X1322248Y68487D03*
X1322415Y75480D03*
X1322906Y94212D03*
X1319968Y98266D03*
X1322906Y109733D03*
X1321747Y136899D03*
X1326826Y138922D03*
X1332002Y142289D03*
X1326974Y144338D03*
X1320880Y143430D03*
X1332654Y154452D03*
X1332268Y159982D03*
X1329620Y227682D03*
X1323912Y245111D03*
X1323694Y266442D03*
X1320387Y258901D03*
X1325769Y259001D03*
X1328745Y732336D03*
X1323345Y769844D03*
X1332947Y767085D03*
X1320032Y775725D03*
X1320786Y1339353D03*
X1318151Y1655269D03*
X1333709Y1655241D03*
X1329331Y1660390D03*
X1341718Y130781D03*
X1348079Y129474D03*
X1336819Y150298D03*
X1339481Y154705D03*
X1343034Y141698D03*
X1337547Y170397D03*
X1337637Y162994D03*
X1337697Y728652D03*
X1338495Y774984D03*
X1345079Y1660508D03*
X1366369Y83820D03*
X1364844Y133782D03*
X1363266Y155703D03*
X1357514Y150092D03*
X1351165Y150861D03*
X1353894Y144872D03*
X1362564Y161142D03*
X1363170Y200872D03*
X1355250Y211002D03*
X1356220Y581862D03*
X1361727Y680665D03*
X1351554Y1325594D03*
X1364860Y1455172D03*
X1375619Y236261D03*
X1374054Y223752D03*
X1378684Y229122D03*
X1381094Y224412D03*
X1370207Y682245D03*
X1369297Y807025D03*
X1375897Y813625D03*
X1382497Y807025D03*
X1370577Y1421899D03*
X1382157Y1408975D03*
X1377075Y1425014D03*
X1386684Y145017D03*
X1386404Y149008D03*
X1394182Y171470D03*
X1398182D03*
X1389097Y813625D03*
X1384638Y1325516D03*
X1396311Y1385712D03*
X1398680Y1380582D03*
X1387074Y1384272D03*
X1390513Y1395452D03*
X1387066Y1401734D03*
X1387291Y1408163D03*
X1392400Y1419825D03*
X1390170Y1423942D03*
X1388557Y1431645D03*
X1395443Y1434700D03*
X1383429Y1427652D03*
X1389220Y1446708D03*
X1391655Y1570037D03*
X1391055Y1565037D03*
X1393000Y1590300D03*
X1401971Y924341D03*
X1401655Y1384676D03*
X1415171Y1383692D03*
X1412608Y1391687D03*
X1414362Y1402191D03*
X1414786Y1426890D03*
X1413440Y1436774D03*
X1409680Y1430613D03*
X1401371Y1434592D03*
X1403350Y1516435D03*
X1400695Y1570037D03*
X1400715Y1565037D03*
X1401300Y1619917D03*
X1400000Y1626362D03*
X1410500Y1638862D03*
X1431430Y251265D03*
X1430097Y726635D03*
X1419697Y792165D03*
X1429697D03*
X1418030Y1325927D03*
X1418990Y1387452D03*
X1415620Y1396652D03*
X1419055Y1392497D03*
X1418870Y1406742D03*
X1423256Y1403728D03*
X1424255Y1396612D03*
X1421371Y1411719D03*
X1421864Y1419730D03*
X1426020Y1521535D03*
X1427120Y1537355D03*
X1427320Y1548575D03*
X1416800Y1564862D03*
X1425620Y1556662D03*
X1428403Y1581378D03*
X1416060Y1574922D03*
X1436335Y309407D03*
X1436050Y321352D03*
X1432487Y712485D03*
X1440150Y730182D03*
X1438457Y737565D03*
X1439697Y792165D03*
X1441357Y845635D03*
X1444874Y925533D03*
X1436470Y925622D03*
X1432125Y924530D03*
X1446807Y1293335D03*
Y1301335D03*
X1444997Y1392885D03*
X1435462Y1396409D03*
X1443112Y1417929D03*
X1445020Y1412672D03*
X1443676Y1432624D03*
X1439742Y1436924D03*
X1434720Y1454862D03*
X1440440Y1454892D03*
X1436330Y1521152D03*
X1436570Y1536972D03*
X1436720Y1548192D03*
X1437140Y1576012D03*
X1446700Y1598400D03*
X1438320Y1668292D03*
X1438220Y1673955D03*
X1446715Y1679957D03*
X1462561Y205982D03*
X1459900Y370823D03*
X1463600Y374462D03*
X1449777Y371039D03*
X1449697Y792165D03*
X1459697D03*
X1454557Y845635D03*
X1450997Y925673D03*
X1448586Y1325395D03*
X1461062Y1413246D03*
X1448620Y1556162D03*
X1448920Y1675062D03*
X1464200Y67802D03*
X1473090Y204502D03*
X1476858Y225448D03*
X1466958Y244948D03*
X1474660Y252878D03*
X1473820Y265962D03*
X1466660Y273878D03*
X1468400Y283709D03*
X1472261Y300182D03*
X1470073Y316202D03*
X1470841Y721493D03*
X1474000Y739362D03*
X1480250Y757753D03*
X1473717Y744674D03*
X1467587Y770665D03*
X1479870Y763842D03*
X1480320Y1338759D03*
X1466448Y1421499D03*
X1470487Y1462965D03*
X1478320Y1522962D03*
X1478061Y1633864D03*
X1493120Y240412D03*
X1490029Y309277D03*
X1494784Y374188D03*
X1486040Y368392D03*
X1493384Y411313D03*
X1482650Y411190D03*
X1495527Y406215D03*
X1489310Y426822D03*
X1494968Y732603D03*
X1489387Y757925D03*
X1491828Y766875D03*
X1486997Y1392015D03*
Y1402015D03*
X1493967Y1418445D03*
X1481918Y1425579D03*
X1482830Y1525162D03*
X1493700Y1665900D03*
X1512420Y239116D03*
X1498984Y282797D03*
X1497817Y292997D03*
Y300997D03*
Y308997D03*
X1505922Y304583D03*
X1505297Y671325D03*
X1508067Y664655D03*
X1496813Y757699D03*
X1510557Y747202D03*
X1502745Y759915D03*
X1512483Y1043233D03*
X1512587Y1323205D03*
Y1333205D03*
X1511357Y1361195D03*
X1510027Y1425825D03*
X1522920Y113030D03*
X1518575Y138662D03*
X1526675Y140117D03*
X1526083Y146225D03*
X1514520Y231116D03*
X1525977Y293444D03*
Y301444D03*
X1517669Y291516D03*
X1518017Y757455D03*
X1526000Y745162D03*
X1523197Y759045D03*
X1518967Y891005D03*
X1520528Y917924D03*
X1527257Y917665D03*
X1522907Y986792D03*
X1523614Y1011464D03*
X1515770Y1028159D03*
X1521528Y1031364D03*
X1526427Y1019785D03*
X1522746Y1048368D03*
X1526746D03*
X1520737Y1061993D03*
X1525787Y1323205D03*
Y1333205D03*
X1516137Y1432135D03*
X1544010Y27552D03*
X1535320Y113062D03*
X1529500Y122122D03*
X1529233Y153162D03*
X1535450Y155262D03*
X1542401Y141561D03*
X1545447Y156035D03*
X1537262Y197834D03*
X1533247Y284324D03*
X1533977Y293444D03*
Y301444D03*
X1540989Y616587D03*
X1541211Y646178D03*
X1530185Y757790D03*
X1531403Y765791D03*
X1540426Y855555D03*
X1540800Y889012D03*
X1531827Y913665D03*
X1535622Y905170D03*
X1544993Y936489D03*
X1543042Y951465D03*
X1535580Y948056D03*
X1536837Y965965D03*
X1530847Y978075D03*
X1532107Y971957D03*
X1538393Y1016271D03*
X1545047Y1030225D03*
X1540227Y1027095D03*
X1543727Y1021175D03*
X1535797Y1037875D03*
X1530467Y1045234D03*
X1536273Y1046561D03*
X1544337Y1042125D03*
X1543667Y1049835D03*
X1532288Y1052545D03*
X1531011Y1660548D03*
X1554239Y138263D03*
X1552960Y124359D03*
X1559387Y589340D03*
X1550487Y681565D03*
X1550320Y696562D03*
X1550917Y704332D03*
X1550390Y709885D03*
X1555937Y1042715D03*
X1563714Y572792D03*
X1564690Y663302D03*
X1562871Y735716D03*
X1567737Y1036815D03*
X1576740Y1080262D03*
X1579632Y787410D03*
X1579816Y793954D03*
X1588459Y1068895D03*
X1603530Y202402D03*
X1604240Y227892D03*
X1608307Y772125D03*
X1609239Y959331D03*
X1602650Y1242752D03*
X1608000Y1261662D03*
X1609403Y1247684D03*
X1623881Y117627D03*
X1623107Y769805D03*
X1616927Y952415D03*
X1623744Y996980D03*
X1620727Y1256225D03*
X1624600Y1262074D03*
X1619454Y1249290D03*
X1624040Y1247202D03*
X1623930Y1252242D03*
X1614116Y1411169D03*
X1636393Y181778D03*
X1633111Y206693D03*
X1642135Y414202D03*
X1638713Y722692D03*
X1639689Y1259345D03*
X1639467Y1250175D03*
X1630643Y1440290D03*
X1636200Y1436862D03*
X1647110Y434177D03*
X1654110D03*
X1658275Y527195D03*
X1649291Y556057D03*
X1645530Y549160D03*
X1645300Y612202D03*
X1653319Y642311D03*
X1648722Y645613D03*
Y679613D03*
X1649455Y711844D03*
X1652807Y769805D03*
X1646627Y952415D03*
Y959265D03*
X1651404Y992838D03*
X1648368Y1245574D03*
X1644714Y1249914D03*
X1649573Y1252942D03*
X1654600Y1262742D03*
X1668100Y180852D03*
X1666690Y193290D03*
X1674432Y216981D03*
X1668426Y222432D03*
X1660861Y227548D03*
X1661110Y434177D03*
X1667376Y515531D03*
X1665790Y523417D03*
X1666840Y544332D03*
X1662467Y530301D03*
X1668917Y549992D03*
X1663502Y555115D03*
X1660660Y602273D03*
X1669489Y1259545D03*
X1661300Y1252085D03*
X1669731Y1248688D03*
X1664867Y1303505D03*
X1671870Y1438296D03*
X1665940Y1512862D03*
X1666123Y1524862D03*
Y1537862D03*
Y1553557D03*
X1666198Y1565557D03*
X1671660Y1569412D03*
X1666198Y1585321D03*
X1690208Y421855D03*
X1689121Y488288D03*
X1681817Y495290D03*
X1686564Y497580D03*
X1675664Y513802D03*
X1690999Y513107D03*
X1683702Y514687D03*
X1676600Y523902D03*
X1687166Y529824D03*
X1684810Y523602D03*
X1688768Y518107D03*
X1685766Y535011D03*
X1685358Y539743D03*
X1679941Y552222D03*
X1678860Y556752D03*
X1683369Y562698D03*
X1683087Y712055D03*
X1686041Y763095D03*
X1676427Y952415D03*
Y959265D03*
X1675642Y989103D03*
X1682942Y1258909D03*
X1679522Y1249489D03*
X1683578Y1253780D03*
X1683500Y1264312D03*
X1678067Y1303505D03*
X1680720Y1487062D03*
X1678340Y1500862D03*
X1677930Y1520362D03*
X1678340Y1541362D03*
X1678230Y1590542D03*
X1703026Y188993D03*
X1699740Y207090D03*
X1693987Y230174D03*
X1703487Y232174D03*
X1698220Y369652D03*
X1702959Y404243D03*
X1707780Y410738D03*
X1697161Y406602D03*
X1692429Y403985D03*
X1701124Y423802D03*
X1694050Y416643D03*
X1695455Y422287D03*
X1707544Y431745D03*
X1707568Y420370D03*
X1697648Y463724D03*
X1693720Y455862D03*
X1702127Y468719D03*
X1697210Y500802D03*
X1694158Y504875D03*
X1707200Y498962D03*
X1699553Y513107D03*
X1707552Y506731D03*
X1707716Y513562D03*
X1702930Y526102D03*
X1701726Y518107D03*
X1699107Y555783D03*
X1703306Y550064D03*
X1692883Y703943D03*
X1701320Y705678D03*
X1693087Y712055D03*
X1696402Y709533D03*
X1706027Y952415D03*
Y959265D03*
X1705242Y989103D03*
X1696061Y1014019D03*
X1705076Y1242032D03*
X1699089Y1258842D03*
X1699431Y1248688D03*
X1699030Y1263912D03*
X1702817Y1374325D03*
X1702417Y1364595D03*
X1691988Y1517803D03*
Y1538803D03*
Y1558262D03*
X1705723Y1583821D03*
X1715210Y18282D03*
X1709589Y26062D03*
X1720895Y68062D03*
X1709000Y87362D03*
X1712720Y111862D03*
X1714180Y154790D03*
X1711599Y197329D03*
X1721220Y458362D03*
X1713977Y457137D03*
X1708977Y458542D03*
X1713158Y478243D03*
X1718786Y467517D03*
X1713977Y470804D03*
X1708977D03*
X1711720Y497964D03*
X1709356Y541144D03*
X1716480Y691410D03*
X1714897Y706095D03*
X1709828Y719283D03*
X1712207Y769805D03*
X1719277Y1013205D03*
X1710363Y1249132D03*
X1713930Y1262074D03*
X1718149Y1496270D03*
X1717149Y1505895D03*
X1717988Y1520951D03*
X1711988D03*
X1717149Y1513945D03*
X1717988Y1530445D03*
X1711988D03*
X1729080Y118132D03*
X1739720Y120892D03*
X1728999Y112895D03*
X1733920Y151362D03*
X1728320Y169862D03*
X1737470Y177147D03*
X1725344Y359334D03*
X1729810Y390620D03*
X1737660D03*
X1734290Y423820D03*
X1739316Y480939D03*
X1728139Y952481D03*
Y959331D03*
X1728924Y987935D03*
X1728477Y1242955D03*
X1728689Y1258845D03*
X1739237Y1256935D03*
X1736715Y1249405D03*
X1727674Y1513945D03*
X1729310Y1520951D03*
X1735310D03*
X1729310Y1530445D03*
X1735310D03*
X1726988Y1554631D03*
Y1547131D03*
X1748720Y97362D03*
X1745010Y122952D03*
X1750820Y119972D03*
X1747591Y171733D03*
X1751068Y262123D03*
X1754245Y269724D03*
X1746484Y279682D03*
X1756204Y301695D03*
X1756933Y372452D03*
X1744380Y382892D03*
X1744510Y377452D03*
X1747080Y435870D03*
X1746720Y464862D03*
X1740886Y493960D03*
X1743440Y721802D03*
X1745541Y763095D03*
X1743710Y1262074D03*
X1742337Y1252300D03*
X1747677Y1507388D03*
X1747304Y1524976D03*
X1741988Y1554631D03*
Y1547131D03*
X1768026Y24165D03*
X1769669Y15244D03*
X1761998Y15187D03*
X1765260Y18262D03*
X1757320Y15872D03*
X1767185Y48817D03*
X1771774Y53682D03*
X1767170Y83607D03*
X1767990Y76797D03*
X1760478Y90027D03*
X1768483Y166260D03*
X1765820Y182282D03*
X1767300Y174587D03*
X1760104Y301648D03*
X1770520Y364148D03*
X1765670Y458012D03*
X1767300Y465893D03*
X1768317Y686375D03*
X1770017Y701175D03*
Y721175D03*
Y711175D03*
X1757839Y952481D03*
Y959331D03*
X1764742Y989103D03*
X1758189Y1258875D03*
X1769037Y1256835D03*
X1759070Y1249412D03*
X1770299Y1249182D03*
X1764163Y1246974D03*
X1758352Y1317368D03*
Y1322168D03*
X1771988Y1554631D03*
Y1547131D03*
X1756988Y1554631D03*
Y1547131D03*
X1775556Y21471D03*
X1775830Y26522D03*
X1779411Y50692D03*
X1774328Y62987D03*
X1775580Y73330D03*
X1787790Y85132D03*
X1781485Y88192D03*
X1785142Y76032D03*
X1773611Y88293D03*
X1780320Y153162D03*
X1774950Y167392D03*
X1779500Y171692D03*
X1782600Y175932D03*
X1777354Y295489D03*
X1782420Y443987D03*
X1773870Y438222D03*
X1781720Y592742D03*
X1773559Y763642D03*
X1787539Y952481D03*
Y959331D03*
X1788219Y1259312D03*
X1773390Y1262074D03*
X1788531Y1248688D03*
X1773480Y1253692D03*
X1788360Y1264522D03*
X1784680Y1553922D03*
X1786988Y1547131D03*
X1797324Y161465D03*
X1799250Y297932D03*
X1803129Y362293D03*
X1802929Y385293D03*
X1792450Y410615D03*
X1792507Y403932D03*
X1792220Y425432D03*
X1792335Y418775D03*
X1804841Y763095D03*
X1794442Y989103D03*
X1802670Y1239522D03*
X1803100Y1262074D03*
X1803357Y1251204D03*
X1795484Y1496401D03*
X1800450Y1505230D03*
X1792645Y1511423D03*
X1795561Y1524729D03*
X1806920Y150862D03*
X1808910Y143902D03*
X1813335Y155435D03*
X1810835Y163986D03*
X1819939Y177243D03*
X1813325Y177257D03*
X1813740Y281712D03*
X1820307Y373829D03*
X1820144Y398052D03*
X1819374Y410432D03*
X1818874Y423932D03*
X1810792Y417432D03*
X1818816Y468872D03*
X1818290Y1232452D03*
X1815474Y1246472D03*
X1814537Y1322105D03*
X1807150Y1505675D03*
X1818004Y1510021D03*
X1818410Y1525815D03*
X1828204Y328654D03*
X1829189Y363731D03*
X1824827Y952415D03*
Y959265D03*
X1824042Y989103D03*
X1829920Y1258322D03*
X1829940Y1263662D03*
X1828510Y1525915D03*
X1841257Y151402D03*
X1838910Y185772D03*
X1844157Y182210D03*
G54D12*
X32370Y147842D03*
X46480Y1574922D03*
X928900Y1185132D03*
X1726300Y1710102D03*
X1796240Y126972D03*
G54D105*
X1360652Y231659D03*
X1362136Y233143D03*
X1363198Y229113D03*
X1364682Y230597D03*
G54D30*
X48333Y444958D03*
X46759D03*
Y439446D03*
X48333D03*
X553063Y109171D03*
X554637D03*
Y114683D03*
X553063D03*
G54D21*
X37721Y760236D03*
Y757676D03*
X54847D03*
Y760236D03*
X1446071Y738216D03*
Y735656D03*
X1463197D03*
Y738216D03*
G54D22*
X40839Y769449D03*
X74169Y381709D03*
X77121Y693098D03*
X80971D03*
X90396Y692430D03*
X109200Y637379D03*
X105400Y639579D03*
X99516Y690740D03*
X99779Y758961D03*
X103779D03*
X107779D03*
X95779D03*
X112497Y513781D03*
X112900Y637979D03*
X126092Y638660D03*
X136029Y758061D03*
X140029D03*
X140104Y1554594D03*
X144029Y758061D03*
X148029D03*
X144120Y1355829D03*
X153789Y1394443D03*
X155100Y1717599D03*
X168562Y394520D03*
X191602Y759382D03*
X187602D03*
X183602D03*
X182727Y1355718D03*
X190332Y1394418D03*
X190971Y1407687D03*
X205320Y673879D03*
X207602Y759382D03*
X203602D03*
X195602D03*
X199602D03*
X209220Y673879D03*
X211602Y759382D03*
X214580Y1355711D03*
X238063Y31270D03*
X248442Y769424D03*
X257342Y768724D03*
X245066Y1254398D03*
X269046Y720186D03*
X265043D03*
X269046Y729981D03*
X273000Y740521D03*
X268870Y744085D03*
X286046Y720186D03*
X282120Y720084D03*
X288646Y749381D03*
X295520Y15254D03*
X298720Y42879D03*
X290720D03*
X294687Y704587D03*
X301038Y720841D03*
Y713702D03*
X297087Y723934D03*
X304602Y730511D03*
X296706Y749325D03*
X300839Y1315708D03*
X306207Y1352564D03*
X302401Y1360053D03*
X306720Y42879D03*
X320656Y723305D03*
X316656D03*
X317967Y740851D03*
X338161Y715307D03*
X327096Y738815D03*
X328656Y723305D03*
X335126Y730815D03*
X336446Y749325D03*
X328620Y1305069D03*
X338300Y1329766D03*
X336179Y1337035D03*
X340446Y749325D03*
X344446D03*
X370902D03*
X362902D03*
X358902D03*
X368391Y1322448D03*
X382902Y749325D03*
X378902D03*
X386902D03*
X372428Y1316440D03*
X383740Y1660499D03*
X390820Y1278379D03*
X400462Y1322109D03*
X405156Y1316805D03*
X416127Y1408182D03*
X431728Y1322084D03*
X424320Y1402079D03*
X430910Y1402089D03*
X432851Y1618354D03*
X436701Y1316246D03*
X450294Y1417486D03*
X440270Y1619289D03*
X444600Y1619449D03*
X460800Y380079D03*
X468831Y1278008D03*
X468790Y1316208D03*
X464191Y1322109D03*
X473013Y1030141D03*
X499510Y81139D03*
X490963Y1277961D03*
X496319Y1335535D03*
X501013Y1329615D03*
X488570Y1413338D03*
X503150Y71489D03*
X507310Y71509D03*
X529720Y35379D03*
X525900Y111217D03*
X530052Y1312623D03*
X533423Y1352564D03*
X528929Y1358608D03*
X539720Y35379D03*
X534720D03*
X542530Y117249D03*
X546370D03*
X554720Y35379D03*
X572500D03*
X568500D03*
X590100Y56879D03*
X597220Y88379D03*
X592220D03*
X595597Y747947D03*
X608250Y749982D03*
X611760Y743987D03*
X599763Y747963D03*
X614750Y757482D03*
Y764482D03*
X608225Y757547D03*
X607340Y883614D03*
X631130Y55799D03*
X624831Y163149D03*
X629002Y163104D03*
X639000Y60379D03*
X635000D03*
X633673Y1253265D03*
X649047Y33627D03*
X664342Y774624D03*
X661942Y1401752D03*
X671942Y770224D03*
X667408Y1394468D03*
X685968Y52699D03*
X690220D03*
X686588Y87354D03*
X696760Y128249D03*
X688247Y381672D03*
X692247D03*
X694720Y486504D03*
X690720D03*
X693310Y757178D03*
X688967Y787509D03*
X696860Y1355997D03*
X707500Y75379D03*
X708110Y82629D03*
X703500Y75379D03*
X712100Y82629D03*
X701362Y757178D03*
X697336D03*
X705388D03*
X710688D03*
X701830Y1401712D03*
X703951Y1394443D03*
X708219Y1634868D03*
X724644Y52062D03*
X729293D03*
X719949D03*
X723400Y82579D03*
X728909Y760721D03*
X714688Y757178D03*
X718688D03*
X728199Y1355736D03*
X724452Y1584035D03*
X724392Y1604280D03*
X716202Y1604263D03*
X737595Y52062D03*
X741377D03*
X733642D03*
X745474D03*
X732501Y74965D03*
X736601D03*
X745220Y511379D03*
X736909Y760721D03*
X745009Y760781D03*
X732909Y760721D03*
X740909D03*
X749477Y52062D03*
X751220Y511379D03*
X753009Y760781D03*
X749009D03*
X757009D03*
X758758Y1666458D03*
X765188Y1585218D03*
X768714Y1666458D03*
X808797Y433442D03*
X808297Y1588300D03*
X833445Y223235D03*
X849767Y1239993D03*
X850415Y1587764D03*
X898087Y462929D03*
X902875D03*
X907420Y466079D03*
X905010Y490804D03*
X892332Y1588160D03*
X911520Y466079D03*
X916111Y509044D03*
X921149Y520073D03*
X919350Y979549D03*
X919300Y990169D03*
X914500Y1663917D03*
X937643Y511867D03*
X926380Y979699D03*
X961445Y381271D03*
X972379Y503808D03*
X960620Y503779D03*
X980092Y412913D03*
X992345D03*
X994956Y424419D03*
X1020069Y299930D03*
X1009000Y380379D03*
X1024099Y299930D03*
X1035688Y390054D03*
X1047500Y384379D03*
X1053749Y760341D03*
X1057749D03*
X1065749D03*
X1061749D03*
X1087196Y760996D03*
X1083296D03*
X1091096D03*
X1098896D03*
X1102796D03*
X1094996D03*
X1115869Y761081D03*
X1106696Y760996D03*
X1119869Y761081D03*
X1110680Y761158D03*
X1105717Y1254898D03*
X1117420Y1392330D03*
X1127869Y761081D03*
X1123869D03*
X1121753Y1438096D03*
X1127100Y1430772D03*
X1126100Y1444799D03*
X1149467Y589039D03*
X1145467D03*
X1142921Y1254694D03*
X1151687Y1577255D03*
X1141687D03*
X1145687D03*
X1153537Y603029D03*
X1153477Y596059D03*
X1163891Y1255121D03*
X1156552Y1392302D03*
X1163643Y1430747D03*
X1164172Y1444046D03*
X1161095Y1577255D03*
X1155687D03*
X1165095D03*
X1172742Y770924D03*
X1179842Y778824D03*
X1171095Y1577255D03*
X1175095D03*
X1197396Y595838D03*
Y602853D03*
X1187891Y1392041D03*
X1228704Y106079D03*
X1228860Y761282D03*
X1222707Y760442D03*
X1249122Y752924D03*
X1242260Y760482D03*
X1235360D03*
X1258195Y126354D03*
X1260544Y228039D03*
X1256193Y730682D03*
X1252847Y738312D03*
X1263937Y742482D03*
X1266723Y103677D03*
X1280291Y242631D03*
X1277257Y733502D03*
X1273257Y733582D03*
X1280797Y740482D03*
X1274198Y747608D03*
X1276980Y1311769D03*
X1282313Y1352564D03*
X1280192Y1359833D03*
X1297821Y100105D03*
X1283485Y112072D03*
X1287641D03*
X1291704Y112111D03*
X1284120Y241659D03*
X1295947Y725242D03*
X1292007Y727252D03*
X1294937Y749482D03*
X1284797Y742202D03*
X1299890Y127259D03*
X1313597Y742312D03*
X1301487Y749812D03*
X1303761Y1313069D03*
X1314441Y1329766D03*
X1312320Y1337035D03*
X1322501Y183116D03*
X1328020Y176238D03*
X1317567Y742322D03*
X1330888Y749526D03*
X1346604Y146449D03*
X1342525D03*
X1343012Y203560D03*
X1334298Y738669D03*
X1344532Y1322448D03*
X1353850Y137189D03*
X1348241Y204038D03*
X1348569Y1316440D03*
X1367420Y1278579D03*
X1381297Y1316805D03*
X1406963Y1402062D03*
X1412842Y1316246D03*
X1426435Y1417486D03*
X1444852Y1278478D03*
X1444931Y1316208D03*
X1449443Y1029830D03*
X1455734Y1395912D03*
X1469067Y731372D03*
X1466984Y1278431D03*
X1477154Y1329615D03*
X1472460Y1335535D03*
X1465747Y1413882D03*
X1478656Y749318D03*
X1490992Y749681D03*
X1486741Y749319D03*
X1503645Y749782D03*
X1509564Y1352564D03*
X1505070Y1358608D03*
X1517575Y741447D03*
X1584000Y749879D03*
X1582000Y756879D03*
X1590915Y758562D03*
X1582017Y900582D03*
X1602788Y758712D03*
X1594997Y758532D03*
X1606788Y758712D03*
X1618788D03*
X1610788D03*
X1614788D03*
X1622077Y1437033D03*
X1638928Y758712D03*
X1630928D03*
X1634928D03*
X1628600Y1428144D03*
X1653220Y615179D03*
X1654667Y759751D03*
X1662276Y540478D03*
X1658679Y759751D03*
X1666686D03*
X1662656D03*
X1658026Y1388743D03*
X1665117Y1428039D03*
X1665666Y1441298D03*
X1685686Y479170D03*
X1703000Y93379D03*
X1699000D03*
X1699150Y505569D03*
X1702848Y760585D03*
X1689565Y1388482D03*
X1710025Y18409D03*
X1713173Y31261D03*
X1708000Y93379D03*
X1708680Y172267D03*
X1707160Y204217D03*
X1710057Y695982D03*
X1709486Y711004D03*
X1714955Y760593D03*
X1710915D03*
X1706948Y760585D03*
X1769791Y31371D03*
X1758075Y40226D03*
X1755378Y228045D03*
X1779575Y13739D03*
X1774435Y13759D03*
G54D13*
X38346Y1420330D03*
X117932Y605380D03*
X763601Y605413D03*
X1094074Y605380D03*
X1739706Y605455D03*
X1819208Y1420330D03*
G54D40*
X177043Y1409115D03*
X184043D03*
X205538Y698226D03*
X219563Y586471D03*
X212563D03*
X219563Y594877D03*
X212563D03*
X219563Y620471D03*
X212563D03*
X219563Y628877D03*
X212563D03*
X219563Y654471D03*
X212563D03*
X219563Y662877D03*
X212563D03*
X212538Y698226D03*
X225113Y1409935D03*
X218113D03*
X240518Y671881D03*
X238478Y699357D03*
X255965Y70636D03*
X255669Y78930D03*
X244518Y568690D03*
X251518D03*
X244518Y602690D03*
X251518D03*
X244518Y595420D03*
X251518D03*
X244518Y636690D03*
X251518D03*
X244518Y629420D03*
X251518D03*
X247518Y671881D03*
X243218Y663720D03*
X250218D03*
X245478Y699357D03*
X262965Y70636D03*
X262669Y78930D03*
X400026Y1157520D03*
Y1165570D03*
X421252Y834842D03*
Y827536D03*
X407772D03*
X414772D03*
X407772Y834842D03*
X414772D03*
X412232Y1032870D03*
X419232D03*
X407026Y1157520D03*
X412526D03*
X419526D03*
X407026Y1165570D03*
X412526D03*
X419526D03*
X428252Y834842D03*
Y827536D03*
X434732D03*
X434729Y834842D03*
X437526Y1157520D03*
X432026D03*
X425026D03*
X432026Y1165570D03*
X425026D03*
X437526D03*
X448212Y827536D03*
X448209Y834842D03*
X441732Y827536D03*
X441729Y834842D03*
X444526Y1157520D03*
X450026D03*
X444526Y1165570D03*
X450026D03*
X461689Y834842D03*
X468689D03*
X461692Y827536D03*
X468692D03*
X455212D03*
X455209Y834842D03*
X468451Y1032870D03*
X461451D03*
X457026Y1157520D03*
X462526D03*
X469526D03*
X457026Y1165570D03*
X462526D03*
X469526D03*
X482169Y834842D03*
X475169D03*
X482172Y827536D03*
X475172D03*
X482026Y1157520D03*
X475026D03*
X482026Y1165570D03*
X475026D03*
X562617Y1321370D03*
Y1330170D03*
X569617Y1321370D03*
Y1330170D03*
X685420Y97062D03*
X692420D03*
X697662Y1409840D03*
X690662D03*
X739880Y1409905D03*
X732880D03*
X940761Y975162D03*
X933761D03*
X1069118Y269600D03*
X1068799Y280874D03*
X1076118Y269600D03*
X1075799Y280874D03*
X1150254Y1445544D03*
X1167444Y182685D03*
X1157254Y1445544D03*
X1174444Y182685D03*
X1193073Y200486D03*
X1186073D03*
X1193069Y193180D03*
X1186069D03*
X1200192Y1437872D03*
X1193192D03*
X1376167Y1157519D03*
Y1165569D03*
X1397393Y827535D03*
Y834841D03*
X1383913D03*
X1390913D03*
X1383913Y827535D03*
X1390913D03*
X1388373Y1032869D03*
X1395373D03*
X1383167Y1157519D03*
X1388667D03*
X1395667D03*
X1383167Y1165569D03*
X1388667D03*
X1395667D03*
X1410873Y827535D03*
X1410870Y834841D03*
X1404393Y827535D03*
Y834841D03*
X1408167Y1157519D03*
X1401167D03*
X1413667D03*
X1408167Y1165569D03*
X1401167D03*
X1413667D03*
X1424353Y827535D03*
X1424350Y834841D03*
X1417873Y827535D03*
X1417870Y834841D03*
X1420667Y1157519D03*
X1426167D03*
X1420667Y1165569D03*
X1426167D03*
X1437833Y827535D03*
X1444833D03*
X1437830Y834841D03*
X1444830D03*
X1431353Y827535D03*
X1431350Y834841D03*
X1444592Y1032869D03*
X1437592D03*
X1433167Y1157519D03*
X1438667D03*
X1445667D03*
X1433167Y1165569D03*
X1438667D03*
X1445667D03*
X1458310Y834841D03*
X1451310D03*
X1458313Y827535D03*
X1451313D03*
X1458167Y1157519D03*
X1451167D03*
X1458167Y1165569D03*
X1451167D03*
X1478658Y293756D03*
X1478758Y285556D03*
X1478658Y301956D03*
X1485658Y293756D03*
X1485758Y285556D03*
X1485858Y316356D03*
X1478858D03*
X1485658Y301956D03*
X1537508Y1330120D03*
Y1338920D03*
X1544508Y1330120D03*
Y1338920D03*
X1607955Y589185D03*
Y616701D03*
X1602455Y624862D03*
Y658862D03*
Y651592D03*
Y685592D03*
Y692862D03*
Y719592D03*
X1614955Y589185D03*
Y616701D03*
X1609455Y624862D03*
Y658862D03*
Y651592D03*
Y685592D03*
Y692862D03*
Y719592D03*
X1634410Y625705D03*
X1641410D03*
X1634410Y634111D03*
X1641410D03*
X1634410Y668111D03*
X1641410D03*
X1634410Y659705D03*
X1641410D03*
X1634410Y693705D03*
X1641410D03*
X1634410Y702111D03*
X1641410D03*
X1644435Y590356D03*
X1651435D03*
X1651828Y1442736D03*
X1658828D03*
X1701327Y1443735D03*
X1694327D03*
X1729326Y71930D03*
X1736326D03*
X1729130Y80364D03*
X1736130D03*
X1755271Y708121D03*
X1762477Y699940D03*
X1755477D03*
X1762271Y708121D03*
G54D106*
X1879155Y344948D03*
Y468898D03*
D03*
Y592848D03*
D03*
Y716798D03*
D03*
Y840748D03*
X1900275Y-19342D03*
X1889155Y344948D03*
Y468898D03*
D03*
X1900275Y592858D03*
X1889155Y592848D03*
D03*
X1900275Y716808D03*
X1889155Y716798D03*
D03*
X1900275Y840758D03*
D03*
X1889155Y840748D03*
X1900275Y964708D03*
X1910275Y-19342D03*
Y592858D03*
Y716808D03*
Y840758D03*
D03*
Y964708D03*
X1921395Y-19332D03*
X1931395D03*
Y592868D03*
X1921395D03*
X1931395D03*
X1921395D03*
Y1205068D03*
X1931395D03*
X1952395Y-19152D03*
X1942395D03*
Y593048D03*
X1952395D03*
X1942395D03*
X1952395D03*
Y1205248D03*
X1942395D03*
X1963362Y-19190D03*
Y593010D03*
D03*
Y1205210D03*
X1984482Y-19180D03*
X1973362Y-19190D03*
X1984482Y593020D03*
D03*
X1973362Y593010D03*
D03*
X1984482Y1205220D03*
X1973362Y1205210D03*
X1994482Y-19180D03*
Y593020D03*
D03*
Y1205220D03*
X2005452Y-19180D03*
X2015452D03*
Y593020D03*
X2005452D03*
X2015452D03*
X2005452D03*
Y1205220D03*
X2015452D03*
X2026452Y-19000D03*
Y593200D03*
D03*
Y1205400D03*
X2047419Y-19038D03*
X2036452Y-19000D03*
X2047419Y593162D03*
X2036452Y593200D03*
X2047419Y593162D03*
X2036452Y593200D03*
X2047419Y1205362D03*
X2036452Y1205400D03*
X2057419Y-19038D03*
Y593162D03*
D03*
Y1205362D03*
X2068539Y593172D03*
X2078539D03*
Y1205372D03*
X2068539D03*
G54D31*
X70472Y173228D03*
Y236220D03*
G54D23*
X40839Y772416D03*
X74169Y384676D03*
X77121Y696065D03*
X80971D03*
X90396Y695397D03*
X109200Y640346D03*
X105400Y642546D03*
X99516Y693707D03*
X99779Y761928D03*
X103779D03*
X107779D03*
X95779D03*
X112497Y516748D03*
X112900Y640946D03*
X126092Y641627D03*
X136029Y761028D03*
X140029D03*
X140104Y1557561D03*
X144029Y761028D03*
X148029D03*
X144120Y1358796D03*
X153789Y1397410D03*
X155100Y1720566D03*
X168562Y397487D03*
X191602Y762349D03*
X187602D03*
X183602D03*
X182727Y1358685D03*
X190332Y1397385D03*
X190971Y1410654D03*
X205320Y676846D03*
X207602Y762349D03*
X203602D03*
X195602D03*
X199602D03*
X209220Y676846D03*
X211602Y762349D03*
X214580Y1358678D03*
X238063Y34237D03*
X248442Y772391D03*
X257342Y771691D03*
X245066Y1257365D03*
X269046Y732948D03*
Y723153D03*
X265043D03*
X273000Y743488D03*
X268870Y747052D03*
X286046Y723153D03*
X282120Y723051D03*
X288646Y752348D03*
X295520Y18221D03*
X298720Y45846D03*
X290720D03*
X301038Y716669D03*
X294687Y707554D03*
X297087Y726901D03*
X301038Y723808D03*
X304602Y733478D03*
X296706Y752292D03*
X300839Y1318675D03*
X306207Y1355531D03*
X302401Y1363020D03*
X306720Y45846D03*
X320656Y726272D03*
X316656D03*
X317967Y743818D03*
X338161Y718274D03*
X328656Y726272D03*
X335126Y733782D03*
X327096Y741782D03*
X336446Y752292D03*
X328620Y1308036D03*
X338300Y1332733D03*
X336179Y1340002D03*
X340446Y752292D03*
X344446D03*
X370902D03*
X362902D03*
X358902D03*
X368391Y1325415D03*
X382902Y752292D03*
X378902D03*
X386902D03*
X372428Y1319407D03*
X383740Y1663466D03*
X390820Y1281346D03*
X400462Y1325076D03*
X405156Y1319772D03*
X416127Y1411149D03*
X431728Y1325051D03*
X424320Y1405046D03*
X430910Y1405056D03*
X432851Y1621321D03*
X436701Y1319213D03*
X450294Y1420453D03*
X440270Y1622256D03*
X444600Y1622416D03*
X460800Y383046D03*
X468831Y1280975D03*
X468790Y1319175D03*
X464191Y1325076D03*
X473013Y1033108D03*
X499510Y84106D03*
X490963Y1280928D03*
X496319Y1338502D03*
X501013Y1332582D03*
X488570Y1416305D03*
X503150Y74456D03*
X507310Y74476D03*
X529720Y38346D03*
X525900Y114184D03*
X530052Y1315590D03*
X533423Y1355531D03*
X528929Y1361575D03*
X539720Y38346D03*
X534720D03*
X542530Y120216D03*
X546370D03*
X554720Y38346D03*
X572500D03*
X568500D03*
X590100Y59846D03*
X597220Y91346D03*
X592220D03*
X595597Y750914D03*
X608250Y752949D03*
X611760Y746954D03*
X599763Y750930D03*
X614750Y760449D03*
Y767449D03*
X608225Y760514D03*
X607340Y886581D03*
X631130Y58766D03*
X624831Y166116D03*
X629002Y166071D03*
X639000Y63346D03*
X635000D03*
X633673Y1256232D03*
X649047Y36594D03*
X664342Y777591D03*
X661942Y1404719D03*
X671942Y773191D03*
X667408Y1397435D03*
X685968Y55666D03*
X690220D03*
X686588Y90321D03*
X696760Y131216D03*
X688247Y384639D03*
X692247D03*
X694720Y489471D03*
X690720D03*
X693310Y760145D03*
X688967Y790476D03*
X696860Y1358964D03*
X707500Y78346D03*
X708110Y85596D03*
X703500Y78346D03*
X712100Y85596D03*
X701362Y760145D03*
X697336D03*
X705388D03*
X710688D03*
X701830Y1404679D03*
X703951Y1397410D03*
X708219Y1637835D03*
X724644Y55029D03*
X729293D03*
X719949D03*
X723400Y85546D03*
X728909Y763688D03*
X714688Y760145D03*
X718688D03*
X728199Y1358703D03*
X724452Y1587002D03*
X724392Y1607247D03*
X716202Y1607230D03*
X737595Y55029D03*
X741377D03*
X733642D03*
X745474D03*
X732501Y77932D03*
X736601D03*
X745220Y514346D03*
X736909Y763688D03*
X745009Y763748D03*
X732909Y763688D03*
X740909D03*
X749477Y55029D03*
X751220Y514346D03*
X753009Y763748D03*
X749009D03*
X757009D03*
X758758Y1669425D03*
X765188Y1588185D03*
X768714Y1669425D03*
X808797Y436409D03*
X808297Y1591267D03*
X833445Y226202D03*
X849767Y1242960D03*
X850415Y1590731D03*
X898087Y465896D03*
X902875D03*
X907420Y469046D03*
X905010Y493771D03*
X892332Y1591127D03*
X911520Y469046D03*
X916111Y512011D03*
X921149Y523040D03*
X919350Y982516D03*
X919300Y993136D03*
X914500Y1666884D03*
X937643Y514834D03*
X926380Y982666D03*
X961445Y384238D03*
X972379Y506775D03*
X960620Y506746D03*
X980092Y415880D03*
X992345D03*
X994956Y427386D03*
X1020069Y302897D03*
X1009000Y383346D03*
X1024099Y302897D03*
X1035688Y393021D03*
X1047500Y387346D03*
X1053749Y763308D03*
X1057749D03*
X1065749D03*
X1061749D03*
X1087196Y763963D03*
X1083296D03*
X1091096D03*
X1098896D03*
X1102796D03*
X1094996D03*
X1115869Y764048D03*
X1106696Y763963D03*
X1119869Y764048D03*
X1110680Y764125D03*
X1105717Y1257865D03*
X1117420Y1395297D03*
X1127869Y764048D03*
X1123869D03*
X1127100Y1433739D03*
X1121753Y1441063D03*
X1126100Y1447766D03*
X1149467Y592006D03*
X1145467D03*
X1142921Y1257661D03*
X1151687Y1580222D03*
X1141687D03*
X1145687D03*
X1153537Y605996D03*
X1153477Y599026D03*
X1163891Y1258088D03*
X1156552Y1395269D03*
X1163643Y1433714D03*
X1164172Y1447013D03*
X1161095Y1580222D03*
X1155687D03*
X1165095D03*
X1172742Y773891D03*
X1179842Y781791D03*
X1171095Y1580222D03*
X1175095D03*
X1197396Y598805D03*
Y605820D03*
X1187891Y1395008D03*
X1228704Y109046D03*
X1228860Y764249D03*
X1222707Y763409D03*
X1249122Y755891D03*
X1242260Y763449D03*
X1235360D03*
X1258195Y129321D03*
X1260544Y231006D03*
X1256193Y733649D03*
X1252847Y741279D03*
X1263937Y745449D03*
X1266723Y106644D03*
X1280291Y245598D03*
X1277257Y736469D03*
X1273257Y736549D03*
X1280797Y743449D03*
X1274198Y750575D03*
X1276980Y1314736D03*
X1282313Y1355531D03*
X1280192Y1362800D03*
X1297821Y103072D03*
X1283485Y115039D03*
X1287641D03*
X1291704Y115078D03*
X1284120Y244626D03*
X1295947Y728209D03*
X1292007Y730219D03*
X1294937Y752449D03*
X1284797Y745169D03*
X1299890Y130226D03*
X1313597Y745279D03*
X1301487Y752779D03*
X1303761Y1316036D03*
X1314441Y1332733D03*
X1312320Y1340002D03*
X1328020Y179205D03*
X1322501Y186083D03*
X1317567Y745289D03*
X1330888Y752493D03*
X1346604Y149416D03*
X1342525D03*
X1343012Y206527D03*
X1334298Y741636D03*
X1344532Y1325415D03*
X1353850Y140156D03*
X1348241Y207005D03*
X1348569Y1319407D03*
X1367420Y1281546D03*
X1381297Y1319772D03*
X1406963Y1405029D03*
X1412842Y1319213D03*
X1426435Y1420453D03*
X1444852Y1281445D03*
X1444931Y1319175D03*
X1449443Y1032797D03*
X1455734Y1398879D03*
X1469067Y734339D03*
X1466984Y1281398D03*
X1477154Y1332582D03*
X1472460Y1338502D03*
X1465747Y1416849D03*
X1478656Y752285D03*
X1490992Y752648D03*
X1486741Y752286D03*
X1503645Y752749D03*
X1509564Y1355531D03*
X1505070Y1361575D03*
X1517575Y744414D03*
X1584000Y752846D03*
X1582000Y759846D03*
X1590915Y761529D03*
X1582017Y903549D03*
X1602788Y761679D03*
X1594997Y761499D03*
X1606788Y761679D03*
X1618788D03*
X1610788D03*
X1614788D03*
X1622077Y1440000D03*
X1638928Y761679D03*
X1630928D03*
X1634928D03*
X1628600Y1431111D03*
X1653220Y618146D03*
X1654667Y762718D03*
X1662276Y543445D03*
X1658679Y762718D03*
X1666686D03*
X1662656D03*
X1658026Y1391710D03*
X1665117Y1431006D03*
X1665666Y1444265D03*
X1685686Y482137D03*
X1703000Y96346D03*
X1699000D03*
X1699150Y508536D03*
X1702848Y763552D03*
X1689565Y1391449D03*
X1710025Y21376D03*
X1713173Y34228D03*
X1708000Y96346D03*
X1708680Y175234D03*
X1707160Y207184D03*
X1710057Y698949D03*
X1709486Y713971D03*
X1714955Y763560D03*
X1710915D03*
X1706948Y763552D03*
X1769791Y34338D03*
X1758075Y43193D03*
X1755378Y231012D03*
X1779575Y16706D03*
X1774435Y16726D03*
G54D14*
X49280Y337402D03*
X41870Y1511291D03*
X441043Y1672205D03*
Y1718465D03*
X1416437Y1672204D03*
Y1718464D03*
X1808192Y1569255D03*
X1812980Y502472D03*
G54D107*
X1879155Y354948D03*
Y458898D03*
Y478898D03*
Y582848D03*
Y602848D03*
Y706798D03*
Y726798D03*
Y830748D03*
X1900275Y-9342D03*
X1889155Y354948D03*
Y458898D03*
Y478898D03*
X1900275Y582858D03*
X1889155Y582848D03*
Y602848D03*
Y706798D03*
X1900275Y726808D03*
X1889155Y726798D03*
X1900275Y830758D03*
X1889155Y830748D03*
X1900275Y850758D03*
Y954708D03*
X1910275Y-9342D03*
Y582858D03*
Y726808D03*
Y830758D03*
Y850758D03*
Y954708D03*
X1921395Y-9332D03*
X1931395D03*
Y582868D03*
X1921395D03*
X1931395Y602868D03*
X1921395D03*
Y1195068D03*
X1931395D03*
X1942395Y-9152D03*
Y583048D03*
Y603048D03*
Y1195248D03*
X1963362Y-9190D03*
X1952395Y-9152D03*
X1963362Y583010D03*
X1952395Y583048D03*
X1963362Y603010D03*
X1952395Y603048D03*
X1963362Y1195210D03*
X1952395Y1195248D03*
X1973362Y-9190D03*
Y583010D03*
Y603010D03*
Y1195210D03*
X1994482Y-9180D03*
X1984482D03*
Y583020D03*
X1994482D03*
X1984482Y603020D03*
X1994482D03*
Y1195220D03*
X1984482D03*
X2005452Y-9180D03*
X2015452D03*
Y583020D03*
X2005452D03*
X2015452Y603020D03*
X2005452D03*
Y1195220D03*
X2015452D03*
X2026452Y-9000D03*
Y583200D03*
Y603200D03*
Y1195400D03*
X2047419Y-9038D03*
X2036452Y-9000D03*
X2047419Y583162D03*
X2036452Y583200D03*
X2047419Y603162D03*
X2036452Y603200D03*
X2047419Y1195362D03*
X2036452Y1195400D03*
X2057419Y-9038D03*
Y583162D03*
Y603162D03*
Y1195362D03*
X2068539Y603172D03*
X2078539D03*
Y1195372D03*
X2068539D03*
G54D41*
X223948Y685639D03*
X230017Y582055D03*
Y616055D03*
Y650055D03*
X255213Y582055D03*
Y616055D03*
Y650055D03*
X249144Y685639D03*
X1047163Y253671D03*
X1072359D03*
X1605129Y602943D03*
X1598760Y638527D03*
Y672527D03*
Y706527D03*
X1623956Y638527D03*
Y672527D03*
Y706527D03*
X1630325Y602943D03*
G54D32*
X86433Y688160D03*
X95849Y716358D03*
X91610Y721414D03*
X121400Y638062D03*
X122575Y671930D03*
X149568Y1395145D03*
X152684Y1403451D03*
X190827D03*
X204610Y605097D03*
Y639097D03*
X249885Y69623D03*
X245220Y67862D03*
X306667Y1361597D03*
X422320Y1383862D03*
X419861Y1429718D03*
X485141Y1405430D03*
X663187Y1395170D03*
X666303Y1403476D03*
X726810Y1652430D03*
X722630Y1655740D03*
X735300Y1648760D03*
X760469Y442647D03*
X774982Y446908D03*
X769452Y1584393D03*
X812698Y1587047D03*
X854777Y1586968D03*
X877322Y296051D03*
X896672Y1587073D03*
X1012791Y157596D03*
X1084000Y1647110D03*
X1122879Y1431474D03*
X1125995Y1439780D03*
X1164138D03*
X1379192Y1325373D03*
X1393630Y1426562D03*
X1411320Y1325373D03*
X1443448D03*
X1451198Y1403047D03*
X1624353Y1428766D03*
X1627469Y1437072D03*
X1657755Y517910D03*
X1649363Y649485D03*
Y683485D03*
Y717485D03*
X1669222Y604490D03*
X1665612Y1437072D03*
X1689095Y462640D03*
X1690229Y481845D03*
X1689544Y543874D03*
X1689506Y539882D03*
X1701811Y501318D03*
X1693711Y498527D03*
X1705035Y729210D03*
X1716148Y483720D03*
X1716087Y495665D03*
X1716156Y487685D03*
X1716278Y491676D03*
X1710122Y703509D03*
G54D50*
X338042Y849978D03*
X345178Y854584D03*
X348878Y880219D03*
X363679Y893036D03*
X375211Y1099017D03*
X393279Y893036D03*
X404378Y899445D03*
X406229Y915466D03*
X402529Y921875D03*
X400679Y944304D03*
X402529Y966735D03*
Y960326D03*
X401111Y1028523D03*
X406662Y1057361D03*
X402962Y1063770D03*
X401111Y1054157D03*
X409929Y896240D03*
X415478Y893036D03*
X422878D03*
X419178Y899445D03*
X422878Y912262D03*
X411779Y918670D03*
X415911Y1047749D03*
X408511D03*
X417762Y1057361D03*
X421462Y1050952D03*
X417762Y1063770D03*
Y1076587D03*
X412211Y1073383D03*
X417762Y1070178D03*
X412211Y1066974D03*
X419612Y1099017D03*
X414061Y1095813D03*
X430278Y893036D03*
X437678D03*
X426578Y899445D03*
X433978D03*
Y905853D03*
X426578D03*
X430279Y925079D03*
X432130Y934692D03*
X435830Y928283D03*
X427012Y1041340D03*
X432561Y1057361D03*
X428862Y1050952D03*
X423311Y1060565D03*
X428861Y1063770D03*
X432560Y1070178D03*
X425162D03*
X441378Y899445D03*
X445078Y893036D03*
X452479D03*
X448778Y899445D03*
X445079Y905853D03*
X452479D03*
X448780Y912262D03*
X441380D03*
X448779Y918670D03*
X454329Y915466D03*
X446930Y934692D03*
X443230Y928283D03*
X450630D03*
X439530Y934692D03*
X449211Y1054157D03*
X449213Y1060565D03*
X454762Y1050952D03*
Y1057361D03*
X451061Y1076587D03*
X451062Y1070178D03*
X459878Y893036D03*
X467278D03*
X456178Y899445D03*
X463578D03*
X470978D03*
X470980Y912262D03*
X470978Y918670D03*
X467278Y905853D03*
X461729Y909057D03*
X459878Y918670D03*
X465429Y921875D03*
X467711Y1047750D03*
X460311D03*
X471411Y1041340D03*
X456611D03*
X464011D03*
Y1054157D03*
X460311Y1060565D03*
X458460Y1070178D03*
X464011Y1066974D03*
X469560Y1070178D03*
X464011Y1073383D03*
X476529Y896240D03*
X478380Y912262D03*
X478379Y918670D03*
X478378Y905853D03*
X480228Y960326D03*
X482078Y982756D03*
X478379Y969939D03*
X475111Y1047749D03*
X478811Y1034931D03*
Y1066974D03*
X475111Y1073383D03*
X482511D03*
X530178Y893036D03*
X650599Y766798D03*
X667677Y441636D03*
X666741Y1255381D03*
X680928Y440061D03*
X671479Y443211D03*
X680928Y458959D03*
X677778Y468407D03*
X671479Y481006D03*
X667350Y470680D03*
X671479Y474707D03*
X684077Y433761D03*
X687227Y458959D03*
X696676Y471557D03*
X693526Y477856D03*
X731322Y421163D03*
X728172Y424313D03*
X731322Y440061D03*
X718723Y462108D03*
X726141Y1255381D03*
X737621Y424313D03*
X785541Y1255381D03*
X815241D03*
X1030780Y1266532D03*
X1088262Y1252293D03*
X1074480Y1263742D03*
X1133200Y1255702D03*
X1138783Y1255381D03*
X1168483D03*
X1181941Y766798D03*
X1224189Y1259155D03*
X1296999Y179649D03*
Y190749D03*
Y201849D03*
X1300393Y235762D03*
X1306617Y177799D03*
X1303407Y190749D03*
X1313025Y188899D03*
X1309833Y220349D03*
X1306627Y214799D03*
X1316242Y209249D03*
X1314184Y849978D03*
X1329062Y164849D03*
X1326918Y161161D03*
X1332268Y174099D03*
X1325857Y218499D03*
X1321320Y854584D03*
X1325020Y880219D03*
X1342903Y170399D03*
X1343521Y893036D03*
X1360186Y226264D03*
X1351354Y1099017D03*
X1373121Y893036D03*
X1380520Y899445D03*
X1378671Y921875D03*
Y966735D03*
Y960326D03*
X1377253Y1028523D03*
Y1047749D03*
X1377255Y1060565D03*
X1380953Y1054157D03*
X1377254Y1066974D03*
X1399020Y905853D03*
X1384220Y918670D03*
X1391621D03*
X1395753Y1047749D03*
X1384653D03*
X1390204Y1050952D03*
X1393904Y1057361D03*
X1382804Y1063770D03*
X1393904D03*
Y1076587D03*
X1388353Y1073383D03*
X1393904Y1070178D03*
X1388353Y1066974D03*
X1395754Y1099017D03*
X1390203Y1095813D03*
X1406420Y873810D03*
Y905853D03*
X1411971Y934691D03*
X1406420Y925079D03*
Y931488D03*
X1411971Y928283D03*
X1403154Y1041340D03*
X1408703Y1057361D03*
Y1063770D03*
X1399453Y1054157D03*
X1405004Y1050952D03*
X1401304Y1063770D03*
X1399453Y1073383D03*
X1405004Y1070178D03*
X1430471Y909057D03*
X1424921Y905853D03*
X1415671Y909057D03*
X1421222Y912262D03*
X1424921Y918670D03*
X1430471Y915466D03*
X1424921Y931488D03*
X1419371Y928283D03*
X1424921Y925079D03*
X1419371Y934691D03*
X1425353Y1054157D03*
X1425355Y1060565D03*
X1430903Y1050952D03*
X1430904Y1057361D03*
X1427203Y1076587D03*
X1427204Y1070178D03*
X1447120Y899445D03*
X1443420Y912262D03*
X1437871Y909057D03*
X1436020Y918670D03*
X1443420Y905853D03*
X1441571Y921875D03*
X1447553Y1041340D03*
X1436453Y1047750D03*
X1443853D03*
X1432753Y1041340D03*
X1440153D03*
Y1054157D03*
X1436453Y1060565D03*
Y1073383D03*
Y1066974D03*
X1442002Y1070178D03*
X1447553Y1066974D03*
X1452671Y896240D03*
X1454521Y918670D03*
X1454522Y912262D03*
X1448970Y915466D03*
X1454520Y905853D03*
X1456370Y960326D03*
X1458220Y982756D03*
X1454521Y969939D03*
X1451253Y1047749D03*
X1454953Y1034931D03*
X1453104Y1076587D03*
Y1070178D03*
X1458653Y1073383D03*
X1506320Y893036D03*
X1611475Y1259227D03*
X1714440Y1255381D03*
X1821083Y1252034D03*
G54D108*
G01X33465Y1739618D02*
G03X26091Y1732244I0J-7374D01*
G01Y1612316D01*
G02X23638Y1606395I-8375J1D01*
G01X10534Y1593291D01*
G03X8374Y1588078I5211J-5213D01*
G01Y320190D01*
G02X5922Y314269I-8372J-1D01*
G01X2660Y311007D01*
G03X500Y305794I5211J-5213D01*
G01Y54252D01*
G03X7874Y46878I7374J0D01*
G01X43709D01*
G02X52083Y38504I0J-8374D01*
G01Y1966D01*
G03X53549Y500I1466J0D01*
G01X319695D01*
G03X321161Y1966I0J1466D01*
G01Y38504D01*
G02X329535Y46878I8374J0D01*
G01X488591D01*
G02X496965Y38504I0J-8374D01*
G01Y22753D01*
G03X498431Y21287I1466J0D01*
G01X764577D01*
G03X766043Y22753I0J1466D01*
G01Y38504D01*
G02X774417Y46878I8374J0D01*
G01X871260D01*
G03X878634Y54252I0J7374D01*
G01Y131004D01*
G02X887008Y139378I8374J0D01*
G01X1011024D01*
G02X1019398Y131004I0J-8374D01*
G01Y54252D01*
G03X1026772Y46878I7374J0D01*
G01X1518118D01*
G02X1526492Y38504I0J-8374D01*
G01Y1966D01*
G03X1527958Y500I1466J0D01*
G01X1794105D01*
G03X1795571Y1966I0J1466D01*
G01Y38504D01*
G02X1803945Y46878I8374J0D01*
G01X1849606D01*
G03X1856980Y54252I0J7374D01*
G01Y305794D01*
G03X1854820Y311007I-7375J-2D01*
G01X1845653Y320174D01*
G02X1843201Y326095I5923J5921D01*
G01Y1593983D01*
G03X1841041Y1599196I-7375J-2D01*
G01X1833842Y1606395D01*
G02X1831390Y1612316I5923J5921D01*
G01Y1732244D01*
G03X1824016Y1739618I-7374J0D01*
G01X1091791D01*
G03X1090323Y1738150I0J-1468D01*
G01Y1736890D01*
G02X1087854Y1734421I-2469J0D01*
G01X769705D01*
G02X767236Y1736890I0J2469D01*
G01Y1738150D01*
G03X765768Y1739618I-1468J0D01*
G01X33465D01*
G54D24*
X33583Y1256964D03*
Y1252965D03*
X48742Y393408D03*
X48575Y386993D03*
X49583Y1256964D03*
X65412Y443677D03*
X71374Y763164D03*
X63283Y1256964D03*
X87762Y659641D03*
Y663141D03*
X90024Y667952D03*
X91992Y673881D03*
Y677881D03*
X88962Y725640D03*
X92983Y1256964D03*
X79283D03*
X107934Y505374D03*
Y509374D03*
Y517925D03*
X99427Y649839D03*
X99497Y642149D03*
X99467Y646009D03*
X108983Y1256964D03*
X120208Y501638D03*
X120238Y507877D03*
Y512983D03*
X127084Y646822D03*
X125092Y667700D03*
X122683Y1256964D03*
Y1250499D03*
X143724Y1257952D03*
X157102Y511095D03*
X146982Y522771D03*
X146332Y694970D03*
X146232Y703270D03*
X152383Y1256964D03*
X152746Y1546009D03*
X145140Y1598155D03*
Y1602666D03*
X168383Y1256964D03*
X182083D03*
X198083D03*
X211783D03*
X241351Y1257456D03*
X227583Y1257520D03*
X257351Y1255756D03*
Y1251564D03*
X261750Y958053D03*
X330709Y205049D03*
X396393Y1412991D03*
Y1416491D03*
X414031Y929165D03*
X419915Y1415275D03*
X406388Y1418492D03*
X408004Y1413662D03*
X435809Y1626419D03*
X451984Y341362D03*
X449454Y1427968D03*
X461484Y341362D03*
X453033Y1411678D03*
X480907Y1402364D03*
X478384Y1408172D03*
X570449Y114132D03*
X570389Y109622D03*
X588490Y747887D03*
X611845Y145473D03*
X612012Y151888D03*
X613122Y774712D03*
X608614Y891364D03*
Y895384D03*
X619734Y34652D03*
X626774Y61272D03*
X619704Y442862D03*
Y457862D03*
Y452862D03*
Y447862D03*
Y462862D03*
X634704Y421362D03*
X649704Y416362D03*
Y431362D03*
Y457862D03*
Y452862D03*
Y447862D03*
Y462862D03*
X656213Y973428D03*
X656547Y989241D03*
Y985321D03*
X656483Y1256964D03*
X669464Y202362D03*
Y206362D03*
Y210362D03*
X673869Y1255932D03*
X687166Y35057D03*
X686183Y1256964D03*
X702747Y412255D03*
X702509Y417500D03*
X702469Y421540D03*
X711204Y484862D03*
Y488862D03*
X707996Y1595623D03*
X708203Y1641851D03*
X718984Y82562D03*
X717531Y412269D03*
X715883Y1256964D03*
X713704Y1301162D03*
Y1297162D03*
X725736Y1593913D03*
X741204Y408362D03*
Y404362D03*
X731944Y411382D03*
X745735Y1257681D03*
X732016Y1249625D03*
X750504Y74562D03*
X757596Y1581783D03*
Y1577203D03*
X763704Y413212D03*
Y408212D03*
Y423212D03*
Y418212D03*
X762824Y469862D03*
Y464862D03*
X777792Y484802D03*
X777824Y488862D03*
X762829Y501662D03*
X762841Y497658D03*
X770171Y753179D03*
X775283Y1256964D03*
X763301Y1257572D03*
X778797Y432665D03*
X791491Y432555D03*
X802004Y139262D03*
Y144262D03*
X800874Y308062D03*
X804983Y1256964D03*
X813148Y276820D03*
X813202Y284311D03*
X834683Y1256964D03*
X852715Y301542D03*
X852874Y308852D03*
X863049Y269220D03*
X895465Y506875D03*
X906058Y507348D03*
X906564Y500117D03*
Y503631D03*
X912068Y493611D03*
X922384Y986242D03*
X931409Y197612D03*
X937852Y505977D03*
X937847Y501925D03*
X937878Y498083D03*
X969273Y386189D03*
X958181Y403656D03*
Y399401D03*
X969284Y402017D03*
X969340Y398138D03*
X960090Y1559276D03*
X960130Y1563256D03*
X1003484Y380862D03*
X994484Y387362D03*
Y383362D03*
Y391362D03*
X994565Y400607D03*
X1004730Y422682D03*
X1015814Y194609D03*
X1018747Y420548D03*
X1009719Y1257810D03*
Y1253869D03*
X1022644Y194609D03*
X1025725Y1256944D03*
X1031939Y1251503D03*
X1039425Y1256944D03*
X1069125D03*
Y1251277D03*
X1098825Y1256944D03*
X1095456Y1251409D03*
X1119891Y1253449D03*
X1128525Y1256944D03*
X1134945Y1251483D03*
X1158225Y1256944D03*
X1174484Y1020362D03*
X1191642Y220362D03*
X1196257Y588714D03*
X1187925Y1256944D03*
X1204371Y599133D03*
X1204731Y605605D03*
X1230577Y116962D03*
X1231577Y134262D03*
X1220217Y126942D03*
X1220184Y134600D03*
X1220214Y130810D03*
X1232107Y156672D03*
X1233494Y192482D03*
X1242204Y193362D03*
X1242077Y217462D03*
X1242104Y221562D03*
X1253069Y120107D03*
X1253070Y124107D03*
X1255637Y752449D03*
X1272848Y196622D03*
X1273077Y229462D03*
Y225462D03*
X1316191Y731375D03*
X1326267Y737747D03*
X1345075Y120618D03*
X1337093Y179062D03*
Y183068D03*
X1343570Y195530D03*
X1337219Y187059D03*
X1337181Y191009D03*
X1343521Y199534D03*
X1342118Y212239D03*
X1333784Y204900D03*
X1359046Y128285D03*
X1352076Y124718D03*
X1365646Y124123D03*
Y128285D03*
X1373450Y1402334D03*
X1372534Y1416491D03*
Y1412791D03*
X1390371Y928806D03*
X1396056Y1415275D03*
X1384429Y1413792D03*
Y1417304D03*
X1425465Y1427948D03*
X1429584Y721944D03*
X1429581Y717865D03*
X1434744Y732212D03*
X1429160Y1412108D03*
X1456204Y149362D03*
Y153362D03*
Y161862D03*
Y165862D03*
Y157862D03*
Y173862D03*
Y177862D03*
Y181862D03*
Y169862D03*
X1454457Y1408139D03*
X1467704Y145362D03*
X1463191Y746305D03*
X1484533Y309257D03*
X1592082Y215568D03*
X1592062Y207567D03*
X1592046Y235982D03*
X1607404Y725062D03*
X1613004Y583362D03*
X1632625Y1256944D03*
X1643203Y647963D03*
X1649282Y653741D03*
X1643203Y681963D03*
X1649282Y687742D03*
X1649400Y721761D03*
X1643203Y715963D03*
X1648710Y1257492D03*
X1670017Y539680D03*
X1669531Y534524D03*
X1657713Y536071D03*
Y532071D03*
X1669987Y528335D03*
X1657713Y544622D03*
X1662325Y1256944D03*
X1682162Y479078D03*
Y482590D03*
X1697654Y198330D03*
X1697634Y202470D03*
X1696706Y475583D03*
X1696670Y486806D03*
X1697444Y481422D03*
X1696760Y537507D03*
X1692025Y1256944D03*
X1716247Y39654D03*
Y43654D03*
Y47654D03*
Y51654D03*
X1707054Y199720D03*
X1721725Y1256944D03*
X1751425D03*
X1761096Y716448D03*
X1761196Y724648D03*
X1781125Y1256944D03*
X1796773Y1253019D03*
Y1256819D03*
X1812806Y1510437D03*
G54D15*
X45775Y393408D03*
X45608Y386993D03*
X30616Y1256964D03*
Y1252965D03*
X62445Y443677D03*
X60316Y1256964D03*
X46616D03*
X68407Y763164D03*
X76316Y1256964D03*
X84795Y659641D03*
Y663141D03*
X87057Y667952D03*
X89025Y673881D03*
Y677881D03*
X85995Y725640D03*
X90016Y1256964D03*
X104967Y505374D03*
Y509374D03*
Y517925D03*
X96460Y649839D03*
X96530Y642149D03*
X96500Y646009D03*
X106016Y1256964D03*
X117241Y501638D03*
X117271Y507877D03*
Y512983D03*
X124117Y646822D03*
X122125Y667700D03*
X119716Y1256964D03*
Y1250499D03*
X143365Y694970D03*
X143265Y703270D03*
X140757Y1257952D03*
X142173Y1598155D03*
Y1602666D03*
X154135Y511095D03*
X144015Y522771D03*
X149416Y1256964D03*
X149779Y1546009D03*
X165416Y1256964D03*
X179116D03*
X208816D03*
X195116D03*
X224616Y1257520D03*
X238384Y1257456D03*
X254384Y1255756D03*
Y1251564D03*
X258783Y958053D03*
X327742Y205049D03*
X403421Y1418492D03*
X393426Y1412991D03*
Y1416491D03*
X411064Y929165D03*
X416948Y1415275D03*
X405037Y1413662D03*
X432842Y1626419D03*
X449017Y341362D03*
X450066Y1411678D03*
X446487Y1427968D03*
X458517Y341362D03*
X477940Y1402364D03*
X475417Y1408172D03*
X567482Y114132D03*
X567422Y109622D03*
X585523Y747887D03*
X608878Y145473D03*
X609045Y151888D03*
X610155Y774712D03*
X605647Y891364D03*
Y895384D03*
X616767Y34652D03*
X623807Y61272D03*
X631737Y421362D03*
X616737Y442862D03*
Y457862D03*
Y452862D03*
Y447862D03*
Y462862D03*
X646737Y416362D03*
Y431362D03*
Y457862D03*
Y452862D03*
Y447862D03*
Y462862D03*
X653246Y973428D03*
X653580Y989241D03*
Y985321D03*
X653516Y1256964D03*
X666497Y202362D03*
Y206362D03*
Y210362D03*
X670902Y1255932D03*
X684199Y35057D03*
X683216Y1256964D03*
X699780Y412255D03*
X699542Y417500D03*
X699502Y421540D03*
X708237Y484862D03*
Y488862D03*
X712916Y1256964D03*
X710737Y1301162D03*
Y1297162D03*
X705029Y1595623D03*
X705236Y1641851D03*
X716017Y82562D03*
X714564Y412269D03*
X728977Y411382D03*
X729049Y1249625D03*
X722769Y1593913D03*
X738237Y408362D03*
Y404362D03*
X742768Y1257681D03*
X747537Y74562D03*
X760737Y413212D03*
Y408212D03*
Y423212D03*
Y418212D03*
X759857Y469862D03*
Y464862D03*
X759862Y501662D03*
X759874Y497658D03*
X760334Y1257572D03*
X754629Y1581783D03*
Y1577203D03*
X775830Y432665D03*
X774825Y484802D03*
X774857Y488862D03*
X767204Y753179D03*
X772316Y1256964D03*
X788524Y432555D03*
X799037Y139262D03*
Y144262D03*
X810181Y276820D03*
X810235Y284311D03*
X797907Y308062D03*
X802016Y1256964D03*
X831716D03*
X849748Y301542D03*
X849907Y308852D03*
X860082Y269220D03*
X892498Y506875D03*
X903091Y507348D03*
X903597Y500117D03*
Y503631D03*
X909101Y493611D03*
X919417Y986242D03*
X928442Y197612D03*
X934885Y505977D03*
X934880Y501925D03*
X934911Y498083D03*
X955214Y403656D03*
Y399401D03*
X957123Y1559276D03*
X957163Y1563256D03*
X966306Y386189D03*
X966317Y402017D03*
X966373Y398138D03*
X1000517Y380862D03*
X991517Y387362D03*
Y383362D03*
Y391362D03*
X991598Y400607D03*
X1001763Y422682D03*
X1019677Y194609D03*
X1012847D03*
X1015780Y420548D03*
X1006752Y1257810D03*
Y1253869D03*
X1036458Y1256944D03*
X1022758D03*
X1028972Y1251503D03*
X1066158Y1256944D03*
Y1251277D03*
X1095858Y1256944D03*
X1092489Y1251409D03*
X1116924Y1253449D03*
X1125558Y1256944D03*
X1131978Y1251483D03*
X1155258Y1256944D03*
X1171517Y1020362D03*
X1184958Y1256944D03*
X1188675Y220362D03*
X1193290Y588714D03*
X1217250Y126942D03*
X1217217Y134600D03*
X1217247Y130810D03*
X1201404Y599133D03*
X1201764Y605605D03*
X1227610Y116962D03*
X1228610Y134262D03*
X1229140Y156672D03*
X1230527Y192482D03*
X1239237Y193362D03*
X1239110Y217462D03*
X1239137Y221562D03*
X1250102Y120107D03*
X1250103Y124107D03*
X1252670Y752449D03*
X1269881Y196622D03*
X1270110Y229462D03*
Y225462D03*
X1313224Y731375D03*
X1330817Y204900D03*
X1323300Y737747D03*
X1342108Y120618D03*
X1334126Y179062D03*
Y183068D03*
X1340603Y195530D03*
X1334252Y187059D03*
X1334214Y191009D03*
X1340554Y199534D03*
X1339151Y212239D03*
X1362679Y124123D03*
Y128285D03*
X1356079D03*
X1349109Y124718D03*
X1370483Y1402334D03*
X1369567Y1416491D03*
Y1412791D03*
X1387404Y928806D03*
X1393089Y1415275D03*
X1381462Y1413792D03*
Y1417304D03*
X1426617Y721944D03*
X1426614Y717865D03*
X1426193Y1412108D03*
X1422498Y1427948D03*
X1431777Y732212D03*
X1453237Y149362D03*
Y153362D03*
Y161862D03*
Y165862D03*
Y157862D03*
Y173862D03*
Y177862D03*
Y181862D03*
Y169862D03*
X1460224Y746305D03*
X1451490Y1408139D03*
X1464737Y145362D03*
X1481566Y309257D03*
X1589115Y215568D03*
X1589095Y207567D03*
X1589079Y235982D03*
X1604437Y725062D03*
X1610037Y583362D03*
X1640236Y647963D03*
Y681963D03*
Y715963D03*
X1629658Y1256944D03*
X1654746Y536071D03*
Y532071D03*
Y544622D03*
X1646315Y653741D03*
Y687742D03*
X1646433Y721761D03*
X1645743Y1257492D03*
X1667050Y539680D03*
X1666564Y534524D03*
X1667020Y528335D03*
X1659358Y1256944D03*
X1679195Y479078D03*
Y482590D03*
X1689058Y1256944D03*
X1704087Y199720D03*
X1694687Y198330D03*
X1694667Y202470D03*
X1693739Y475583D03*
X1693703Y486806D03*
X1694477Y481422D03*
X1693793Y537507D03*
X1713280Y39654D03*
Y43654D03*
Y47654D03*
Y51654D03*
X1718758Y1256944D03*
X1748458D03*
X1758129Y716448D03*
X1758229Y724648D03*
X1778158Y1256944D03*
X1793806Y1253019D03*
Y1256819D03*
X1809839Y1510437D03*
G54D42*
X250326Y185236D03*
X368437D03*
G54D51*
X349187Y710632D03*
X351746D03*
X354305D03*
Y718112D03*
X351746D03*
X349187D03*
X1434597Y717132D03*
X1437156D03*
X1439715D03*
Y724612D03*
X1437156D03*
X1434597D03*
X1709521Y185170D03*
X1712080D03*
X1714639D03*
Y192650D03*
X1712080D03*
X1709521D03*
G54D60*
X498487Y103452D03*
Y102074D03*
Y100696D03*
Y99318D03*
Y107586D03*
Y106208D03*
Y104830D03*
X508133Y99318D03*
Y100696D03*
Y102074D03*
Y103452D03*
Y104830D03*
Y106208D03*
Y107586D03*
G54D33*
X109087Y522620D03*
X144640Y510230D03*
X338667Y772452D03*
X341527Y778362D03*
X358902Y773352D03*
X372117Y778576D03*
X381010Y734732D03*
X402700Y234167D03*
X420865Y215067D03*
X433695Y209862D03*
X426490Y244262D03*
X452071Y254862D03*
X461900Y215244D03*
X466300Y217803D03*
X461900Y222921D03*
X466300Y225480D03*
X461736Y301098D03*
X463198Y311587D03*
X470780Y1406980D03*
X486800Y259162D03*
X478500Y258862D03*
X474736Y302098D03*
X479736Y303598D03*
Y308598D03*
X472960Y602152D03*
X498700Y212685D03*
Y220362D03*
X503100Y215244D03*
Y222921D03*
X496028Y258590D03*
X495136Y300398D03*
X495036Y310398D03*
X508500Y232862D03*
X508502Y298813D03*
X508500Y303362D03*
X508136Y309398D03*
X536420Y309422D03*
X563482Y40826D03*
X558058Y46352D03*
X567865Y92656D03*
X570150Y102862D03*
X607630Y39662D03*
X606880Y44682D03*
X638281Y1254922D03*
X831705Y593877D03*
X859888Y593970D03*
X911340Y502872D03*
X912828Y498251D03*
X933012Y516711D03*
X970207Y1562731D03*
X1045760Y596272D03*
X1051680Y614772D03*
X1144810Y613762D03*
X1291306Y863361D03*
X1287674Y856290D03*
X1305288Y858104D03*
X1328187Y774757D03*
X1347640Y101950D03*
X1413900Y225212D03*
X1415340Y231812D03*
X1431430Y256383D03*
Y264060D03*
X1457361Y205982D03*
X1459961Y210432D03*
X1456150Y214382D03*
X1456770Y342942D03*
X1462790Y359042D03*
X1462870Y355012D03*
X1455920Y373941D03*
X1455642Y409646D03*
X1456777Y418596D03*
Y426546D03*
X1467761Y205982D03*
X1471308Y230640D03*
X1471690Y259862D03*
X1467700Y370953D03*
X1472758Y370817D03*
X1465836Y408668D03*
X1470942Y409718D03*
X1475250Y401812D03*
X1481766Y372288D03*
X1489443D03*
X1481766Y406238D03*
X1490384Y407292D03*
X1486880Y416863D03*
X1508959Y215802D03*
X1499922Y211240D03*
X1504484Y234562D03*
X1508410Y230842D03*
X1510017Y225516D03*
X1501840Y225502D03*
X1510810Y249742D03*
X1509040Y243362D03*
X1504890Y249862D03*
X1506600Y239092D03*
X1498184Y361723D03*
Y369798D03*
X1524539Y215551D03*
X1522009Y210825D03*
X1518110Y215551D03*
X1526998Y209645D03*
X1527732Y219488D03*
X1526152Y225114D03*
X1533385Y193108D03*
X1533148Y211614D03*
X1531824Y207677D03*
X1534194Y217519D03*
X1535561Y225393D03*
X1531110Y264862D03*
X1539150Y267132D03*
X1551160Y189342D03*
X1557900Y220362D03*
X1557760Y214792D03*
X1550353Y217352D03*
X1559400Y229832D03*
X1573560Y245078D03*
X1574760Y251032D03*
X1604240Y238242D03*
X1658450Y549550D03*
X1689093Y474538D03*
G54D109*
G01X-6350Y-464479D02*
Y-539479D01*
X493650D01*
Y-464479D01*
X-6350D01*
G01X5650Y-529479D02*
Y-534479D01*
G01X4193Y-529479D02*
X7107D01*
G01X12017Y-534479D02*
X9483D01*
Y-529479D01*
X12017D01*
G01X11003Y-531896D02*
X9483D01*
G01X14583Y-529479D02*
Y-534479D01*
X17117D01*
G01X20950Y-534646D02*
X20823Y-534562D01*
Y-534396D01*
X20950Y-534312D01*
X21077Y-534396D01*
Y-534562D01*
X20950Y-534646D01*
G01Y-532396D02*
X20823Y-532312D01*
Y-532146D01*
X20950Y-532062D01*
X21077Y-532146D01*
Y-532312D01*
X20950Y-532396D01*
G01X25733Y-536146D02*
X25100Y-535312D01*
X24783Y-534479D01*
Y-531146D01*
X25100Y-530312D01*
X25733Y-529479D01*
G01X31150D02*
X30643Y-529646D01*
X30263Y-530062D01*
X30010Y-530562D01*
X29820Y-531229D01*
X29757Y-531979D01*
X29820Y-532729D01*
X30010Y-533396D01*
X30263Y-533896D01*
X30643Y-534312D01*
X31150Y-534479D01*
X31657Y-534312D01*
X32037Y-533896D01*
X32290Y-533396D01*
X32480Y-532729D01*
X32543Y-531979D01*
X32480Y-531229D01*
X32290Y-530562D01*
X32037Y-530062D01*
X31657Y-529646D01*
X31150Y-529479D01*
G01X34857Y-533479D02*
X35237Y-534062D01*
X35743Y-534396D01*
X36313Y-534479D01*
X36820Y-534396D01*
X37327Y-533979D01*
X37643Y-533479D01*
X37707Y-532979D01*
X37580Y-532396D01*
X37137Y-531979D01*
X36693Y-531812D01*
X36123D01*
G01X36693D02*
X37073Y-531562D01*
X37390Y-531146D01*
X37517Y-530646D01*
X37390Y-530146D01*
X37073Y-529729D01*
X36503Y-529479D01*
X35933Y-529562D01*
X35363Y-529896D01*
G01X41667Y-536146D02*
X42300Y-535312D01*
X42617Y-534479D01*
Y-531146D01*
X42300Y-530312D01*
X41667Y-529479D01*
G01X45057Y-533479D02*
X45437Y-534062D01*
X45943Y-534396D01*
X46513Y-534479D01*
X47020Y-534396D01*
X47527Y-533979D01*
X47843Y-533479D01*
X47907Y-532979D01*
X47780Y-532396D01*
X47337Y-531979D01*
X46893Y-531812D01*
X46323D01*
G01X46893D02*
X47273Y-531562D01*
X47590Y-531146D01*
X47717Y-530646D01*
X47590Y-530146D01*
X47273Y-529729D01*
X46703Y-529479D01*
X46133Y-529562D01*
X45563Y-529896D01*
G01X50347Y-530312D02*
X50727Y-529812D01*
X51170Y-529562D01*
X51677Y-529479D01*
X52310Y-529646D01*
X52753Y-530062D01*
X52880Y-530562D01*
X52817Y-531062D01*
X52563Y-531479D01*
X51297Y-532312D01*
X50727Y-532896D01*
X50347Y-533729D01*
X50220Y-534479D01*
X52880D01*
G01X56523D02*
X56650Y-533396D01*
X56840Y-532479D01*
X57093Y-531646D01*
X57410Y-530729D01*
X57917Y-529479D01*
X55383D01*
G01X60927Y-532812D02*
X62573D01*
G01X65647Y-530312D02*
X66027Y-529812D01*
X66470Y-529562D01*
X66977Y-529479D01*
X67610Y-529646D01*
X68053Y-530062D01*
X68180Y-530562D01*
X68117Y-531062D01*
X67863Y-531479D01*
X66597Y-532312D01*
X66027Y-532896D01*
X65647Y-533729D01*
X65520Y-534479D01*
X68180D01*
G01X70557Y-533479D02*
X70937Y-534062D01*
X71443Y-534396D01*
X72013Y-534479D01*
X72520Y-534396D01*
X73027Y-533979D01*
X73343Y-533479D01*
X73407Y-532979D01*
X73280Y-532396D01*
X72837Y-531979D01*
X72393Y-531812D01*
X71823D01*
G01X72393D02*
X72773Y-531562D01*
X73090Y-531146D01*
X73217Y-530646D01*
X73090Y-530146D01*
X72773Y-529729D01*
X72203Y-529479D01*
X71633Y-529562D01*
X71063Y-529896D01*
G01X77810Y-534479D02*
Y-529479D01*
X75467Y-533062D01*
X78633D01*
G01X80757Y-533729D02*
X81137Y-534146D01*
X81580Y-534396D01*
X82150Y-534479D01*
X82720Y-534312D01*
X83163Y-533979D01*
X83480Y-533396D01*
X83543Y-532729D01*
X83417Y-532062D01*
X83100Y-531646D01*
X82657Y-531312D01*
X82213Y-531229D01*
X81770Y-531312D01*
X81200Y-531646D01*
X81390Y-529479D01*
X83100D01*
G01X91147Y-534479D02*
Y-529479D01*
X93553D01*
G01X92667Y-531896D02*
X91147D01*
G01X95867Y-534479D02*
X97450Y-529479D01*
X99033Y-534479D01*
G01X98463Y-532729D02*
X96437D01*
G01X101220Y-534479D02*
X103880Y-529479D01*
G01X101220D02*
X103880Y-534479D01*
G01X107650Y-534646D02*
X107523Y-534562D01*
Y-534396D01*
X107650Y-534312D01*
X107777Y-534396D01*
Y-534562D01*
X107650Y-534646D01*
G01Y-532396D02*
X107523Y-532312D01*
Y-532146D01*
X107650Y-532062D01*
X107777Y-532146D01*
Y-532312D01*
X107650Y-532396D01*
G01X112433Y-536146D02*
X111800Y-535312D01*
X111483Y-534479D01*
Y-531146D01*
X111800Y-530312D01*
X112433Y-529479D01*
G01X117850D02*
X117343Y-529646D01*
X116963Y-530062D01*
X116710Y-530562D01*
X116520Y-531229D01*
X116457Y-531979D01*
X116520Y-532729D01*
X116710Y-533396D01*
X116963Y-533896D01*
X117343Y-534312D01*
X117850Y-534479D01*
X118357Y-534312D01*
X118737Y-533896D01*
X118990Y-533396D01*
X119180Y-532729D01*
X119243Y-531979D01*
X119180Y-531229D01*
X118990Y-530562D01*
X118737Y-530062D01*
X118357Y-529646D01*
X117850Y-529479D01*
G01X121557Y-533479D02*
X121937Y-534062D01*
X122443Y-534396D01*
X123013Y-534479D01*
X123520Y-534396D01*
X124027Y-533979D01*
X124343Y-533479D01*
X124407Y-532979D01*
X124280Y-532396D01*
X123837Y-531979D01*
X123393Y-531812D01*
X122823D01*
G01X123393D02*
X123773Y-531562D01*
X124090Y-531146D01*
X124217Y-530646D01*
X124090Y-530146D01*
X123773Y-529729D01*
X123203Y-529479D01*
X122633Y-529562D01*
X122063Y-529896D01*
G01X128367Y-536146D02*
X129000Y-535312D01*
X129317Y-534479D01*
Y-531146D01*
X129000Y-530312D01*
X128367Y-529479D01*
G01X131757Y-533479D02*
X132137Y-534062D01*
X132643Y-534396D01*
X133213Y-534479D01*
X133720Y-534396D01*
X134227Y-533979D01*
X134543Y-533479D01*
X134607Y-532979D01*
X134480Y-532396D01*
X134037Y-531979D01*
X133593Y-531812D01*
X133023D01*
G01X133593D02*
X133973Y-531562D01*
X134290Y-531146D01*
X134417Y-530646D01*
X134290Y-530146D01*
X133973Y-529729D01*
X133403Y-529479D01*
X132833Y-529562D01*
X132263Y-529896D01*
G01X137173Y-533896D02*
X137617Y-534312D01*
X138123Y-534479D01*
X138630Y-534312D01*
X139073Y-533812D01*
X139390Y-533062D01*
X139517Y-532312D01*
Y-531396D01*
X139390Y-530646D01*
X139073Y-529979D01*
X138693Y-529646D01*
X138250Y-529479D01*
X137743Y-529646D01*
X137363Y-529979D01*
X137110Y-530479D01*
X136983Y-531146D01*
X137110Y-531729D01*
X137427Y-532312D01*
X137807Y-532646D01*
X138250Y-532729D01*
X138757Y-532562D01*
X139137Y-532146D01*
X139517Y-531396D01*
G01X143223Y-534479D02*
X143350Y-533396D01*
X143540Y-532479D01*
X143793Y-531646D01*
X144110Y-530729D01*
X144617Y-529479D01*
X142083D01*
G01X147627Y-532812D02*
X149273D01*
G01X152157Y-533479D02*
X152537Y-534062D01*
X153043Y-534396D01*
X153613Y-534479D01*
X154120Y-534396D01*
X154627Y-533979D01*
X154943Y-533479D01*
X155007Y-532979D01*
X154880Y-532396D01*
X154437Y-531979D01*
X153993Y-531812D01*
X153423D01*
G01X153993D02*
X154373Y-531562D01*
X154690Y-531146D01*
X154817Y-530646D01*
X154690Y-530146D01*
X154373Y-529729D01*
X153803Y-529479D01*
X153233Y-529562D01*
X152663Y-529896D01*
G01X157447Y-532396D02*
X157890Y-531812D01*
X158270Y-531479D01*
X158777Y-531312D01*
X159220Y-531479D01*
X159537Y-531812D01*
X159790Y-532312D01*
X159853Y-532896D01*
X159790Y-533396D01*
X159537Y-533896D01*
X159157Y-534312D01*
X158713Y-534479D01*
X158207Y-534312D01*
X157763Y-533812D01*
X157510Y-533062D01*
X157447Y-532229D01*
X157573Y-531146D01*
X157763Y-530562D01*
X158080Y-529979D01*
X158523Y-529562D01*
X158967Y-529479D01*
X159410Y-529646D01*
X159727Y-530062D01*
G01X163750Y-534479D02*
Y-529479D01*
X162990Y-530479D01*
G01Y-534479D02*
X164510D01*
G01X169610D02*
Y-529479D01*
X167267Y-533062D01*
X170433D01*
G01X188650Y-464479D02*
Y-539479D01*
G01Y-514479D02*
X291650D01*
Y-489479D01*
G01X188650D02*
X291650D01*
G01Y-464479D02*
Y-539479D01*
G01X293650Y-464479D02*
Y-539479D01*
G01X299157Y-524479D02*
Y-519479D01*
X300423D01*
X300930Y-519729D01*
X301310Y-520062D01*
X301627Y-520562D01*
X301880Y-521146D01*
X301943Y-521979D01*
X301880Y-522812D01*
X301627Y-523396D01*
X301310Y-523896D01*
X300930Y-524229D01*
X300423Y-524479D01*
X299157D01*
G01X304067D02*
X305650Y-519479D01*
X307233Y-524479D01*
G01X306663Y-522729D02*
X304637D01*
G01X310750Y-519479D02*
Y-524479D01*
G01X309293Y-519479D02*
X312207D01*
G01X317117Y-524479D02*
X314583D01*
Y-519479D01*
X317117D01*
G01X316103Y-521896D02*
X314583D01*
G01X320950Y-524646D02*
X320823Y-524562D01*
Y-524396D01*
X320950Y-524312D01*
X321077Y-524396D01*
Y-524562D01*
X320950Y-524646D01*
G01Y-522396D02*
X320823Y-522312D01*
Y-522146D01*
X320950Y-522062D01*
X321077Y-522146D01*
Y-522312D01*
X320950Y-522396D01*
G01X299283Y-499479D02*
Y-494479D01*
X300803D01*
X301310Y-494729D01*
X301690Y-495312D01*
X301817Y-495979D01*
X301690Y-496646D01*
X301373Y-497146D01*
X300803Y-497396D01*
X299283D01*
G01X304510Y-499646D02*
X306790Y-494479D01*
G01X309293Y-499479D02*
Y-494479D01*
X312207Y-499479D01*
Y-494479D01*
G01X315850Y-499646D02*
X315723Y-499562D01*
Y-499396D01*
X315850Y-499312D01*
X315977Y-499396D01*
Y-499562D01*
X315850Y-499646D01*
G01Y-497396D02*
X315723Y-497312D01*
Y-497146D01*
X315850Y-497062D01*
X315977Y-497146D01*
Y-497312D01*
X315850Y-497396D01*
G01X293650Y-514479D02*
X493650D01*
G01X293650Y-489479D02*
X493650D01*
G01X299283Y-474479D02*
Y-469479D01*
X300803D01*
X301310Y-469729D01*
X301690Y-470312D01*
X301817Y-470979D01*
X301690Y-471646D01*
X301373Y-472146D01*
X300803Y-472396D01*
X299283D01*
G01X304383Y-474479D02*
Y-469479D01*
X305967D01*
X306473Y-469729D01*
X306790Y-470062D01*
X306917Y-470729D01*
X306790Y-471396D01*
X306410Y-471812D01*
X305967Y-472062D01*
X304383D01*
G01X305967D02*
X306917Y-474479D01*
G01X310750D02*
X310243Y-474396D01*
X309800Y-474062D01*
X309420Y-473562D01*
X309167Y-472979D01*
X309040Y-472312D01*
Y-471646D01*
X309167Y-470979D01*
X309420Y-470396D01*
X309800Y-469896D01*
X310243Y-469562D01*
X310750Y-469479D01*
X311257Y-469562D01*
X311700Y-469896D01*
X312080Y-470396D01*
X312333Y-470979D01*
X312460Y-471646D01*
Y-472312D01*
X312333Y-472979D01*
X312080Y-473562D01*
X311700Y-474062D01*
X311257Y-474396D01*
X310750Y-474479D01*
G01X314583Y-473479D02*
X314900Y-473979D01*
X315280Y-474312D01*
X315723Y-474479D01*
X316230Y-474312D01*
X316610Y-473979D01*
X316990Y-473479D01*
X317117Y-472812D01*
Y-469479D01*
G01X322217Y-474479D02*
X319683D01*
Y-469479D01*
X322217D01*
G01X321203Y-471896D02*
X319683D01*
G01X327443Y-469896D02*
X327063Y-469646D01*
X326620Y-469479D01*
X326113D01*
X325543Y-469729D01*
X325100Y-470146D01*
X324783Y-470646D01*
X324530Y-471479D01*
X324467Y-472229D01*
X324593Y-472979D01*
X324783Y-473479D01*
X325163Y-473979D01*
X325607Y-474312D01*
X326050Y-474479D01*
X326493D01*
X326937Y-474312D01*
X327317Y-474062D01*
X327633Y-473729D01*
G01X331150Y-469479D02*
Y-474479D01*
G01X329693Y-469479D02*
X332607D01*
G01X336250Y-474646D02*
X336123Y-474562D01*
Y-474396D01*
X336250Y-474312D01*
X336377Y-474396D01*
Y-474562D01*
X336250Y-474646D01*
G01Y-472396D02*
X336123Y-472312D01*
Y-472146D01*
X336250Y-472062D01*
X336377Y-472146D01*
Y-472312D01*
X336250Y-472396D01*
G01X408650Y-514479D02*
Y-539479D01*
G01X411283Y-516979D02*
Y-521979D01*
X413817D01*
G01X416890Y-516979D02*
X418410D01*
G01X417650D02*
Y-521979D01*
G01X416890D02*
X418410D01*
G01X423257Y-519312D02*
X423510Y-519062D01*
X423700Y-518646D01*
X423827Y-518062D01*
X423700Y-517562D01*
X423447Y-517229D01*
X423003Y-516979D01*
X421293D01*
Y-521979D01*
X423383D01*
X423827Y-521646D01*
X424080Y-521146D01*
X424207Y-520562D01*
X424080Y-519979D01*
X423700Y-519479D01*
X423257Y-519312D01*
X421293D01*
G01X427850Y-522146D02*
X427723Y-522062D01*
Y-521896D01*
X427850Y-521812D01*
X427977Y-521896D01*
Y-522062D01*
X427850Y-522146D01*
G01Y-519896D02*
X427723Y-519812D01*
Y-519646D01*
X427850Y-519562D01*
X427977Y-519646D01*
Y-519812D01*
X427850Y-519896D01*
G01X451650Y-514479D02*
Y-539479D01*
G01Y-489479D02*
Y-514479D01*
G01X456663Y-541646D02*
X456770Y-541521D01*
X456850Y-541312D01*
X456903Y-541021D01*
X456850Y-540771D01*
X456743Y-540604D01*
X456557Y-540479D01*
X455837D01*
Y-542979D01*
X456717D01*
X456903Y-542812D01*
X457010Y-542562D01*
X457063Y-542271D01*
X457010Y-541979D01*
X456850Y-541729D01*
X456663Y-541646D01*
X455837D01*
G01X459130Y-542979D02*
Y-541312D01*
G01Y-541604D02*
X459023Y-541437D01*
X458863Y-541354D01*
X458677Y-541312D01*
X458490Y-541396D01*
X458330Y-541562D01*
X458223Y-541812D01*
X458170Y-542146D01*
X458223Y-542479D01*
X458330Y-542729D01*
X458490Y-542896D01*
X458677Y-542979D01*
X458863Y-542937D01*
X459023Y-542812D01*
X459130Y-542646D01*
G01X460450Y-542687D02*
X460583Y-542854D01*
X460770Y-542979D01*
X460930D01*
X461090Y-542896D01*
X461197Y-542771D01*
X461250Y-542604D01*
X461223Y-542354D01*
X461117Y-542229D01*
X460637Y-541979D01*
X460530Y-541687D01*
X460583Y-541479D01*
X460690Y-541354D01*
X460850Y-541312D01*
X461010Y-541354D01*
X461170Y-541479D01*
G01X462650Y-541854D02*
X463503D01*
X463423Y-541562D01*
X463290Y-541396D01*
X463103Y-541312D01*
X462917Y-541354D01*
X462757Y-541479D01*
X462650Y-541771D01*
X462597Y-542021D01*
Y-542271D01*
X462650Y-542521D01*
X462783Y-542771D01*
X462943Y-542937D01*
X463130Y-542979D01*
X463317Y-542896D01*
X463503Y-542646D01*
G01X464770Y-542979D02*
Y-540479D01*
G01Y-541729D02*
X464903Y-541479D01*
X465063Y-541354D01*
X465223Y-541312D01*
X465463Y-541396D01*
X465623Y-541562D01*
X465730Y-541854D01*
Y-542187D01*
X465677Y-542521D01*
X465570Y-542771D01*
X465383Y-542937D01*
X465223Y-542979D01*
X465063Y-542937D01*
X464903Y-542812D01*
X464770Y-542604D01*
G01X467450Y-542979D02*
X467290Y-542937D01*
X467130Y-542771D01*
X467023Y-542479D01*
X466970Y-542146D01*
X467023Y-541812D01*
X467130Y-541521D01*
X467290Y-541354D01*
X467450Y-541312D01*
X467610Y-541354D01*
X467770Y-541521D01*
X467877Y-541812D01*
X467903Y-542146D01*
X467877Y-542479D01*
X467770Y-542771D01*
X467610Y-542937D01*
X467450Y-542979D01*
G01X470130D02*
Y-541312D01*
G01Y-541604D02*
X470023Y-541437D01*
X469863Y-541354D01*
X469677Y-541312D01*
X469490Y-541396D01*
X469330Y-541562D01*
X469223Y-541812D01*
X469170Y-542146D01*
X469223Y-542479D01*
X469330Y-542729D01*
X469490Y-542896D01*
X469677Y-542979D01*
X469863Y-542937D01*
X470023Y-542812D01*
X470130Y-542646D01*
G01X471477Y-542979D02*
Y-541312D01*
G01Y-541646D02*
X471610Y-541479D01*
X471743Y-541354D01*
X471930Y-541312D01*
X472063Y-541354D01*
X472223Y-541479D01*
G01X474530Y-540479D02*
Y-542979D01*
G01Y-542604D02*
X474423Y-542812D01*
X474263Y-542937D01*
X474077Y-542979D01*
X473863Y-542896D01*
X473703Y-542687D01*
X473597Y-542437D01*
X473570Y-542146D01*
X473597Y-541854D01*
X473703Y-541604D01*
X473863Y-541396D01*
X474077Y-541312D01*
X474263Y-541354D01*
X474397Y-541437D01*
X474530Y-541604D01*
G01X477917Y-542979D02*
Y-540479D01*
X478583D01*
X478797Y-540604D01*
X478930Y-540771D01*
X478983Y-541104D01*
X478930Y-541437D01*
X478770Y-541646D01*
X478583Y-541771D01*
X477917D01*
G01X478583D02*
X478983Y-542979D01*
G01X480250Y-541854D02*
X481103D01*
X481023Y-541562D01*
X480890Y-541396D01*
X480703Y-541312D01*
X480517Y-541354D01*
X480357Y-541479D01*
X480250Y-541771D01*
X480197Y-542021D01*
Y-542271D01*
X480250Y-542521D01*
X480383Y-542771D01*
X480543Y-542937D01*
X480730Y-542979D01*
X480917Y-542896D01*
X481103Y-542646D01*
G01X482370Y-541312D02*
X482850Y-542979D01*
X483330Y-541312D01*
G01X485050Y-543062D02*
X484997Y-543021D01*
Y-542937D01*
X485050Y-542896D01*
X485103Y-542937D01*
Y-543021D01*
X485050Y-543062D01*
G01X487250Y-542979D02*
X487437Y-542937D01*
X487650Y-542812D01*
X487783Y-542604D01*
X487837Y-542312D01*
X487783Y-542021D01*
X487623Y-541771D01*
X487383Y-541646D01*
X487117D01*
X486957Y-541562D01*
X486823Y-541354D01*
X486770Y-541062D01*
X486850Y-540771D01*
X487037Y-540562D01*
X487250Y-540479D01*
X487463Y-540562D01*
X487650Y-540771D01*
X487730Y-541062D01*
X487677Y-541354D01*
X487543Y-541562D01*
X487383Y-541646D01*
X487117D01*
X486877Y-541771D01*
X486717Y-542021D01*
X486663Y-542312D01*
X486717Y-542604D01*
X486850Y-542812D01*
X487063Y-542937D01*
X487250Y-542979D01*
G01X489663Y-541646D02*
X489770Y-541521D01*
X489850Y-541312D01*
X489903Y-541021D01*
X489850Y-540771D01*
X489743Y-540604D01*
X489557Y-540479D01*
X488837D01*
Y-542979D01*
X489717D01*
X489903Y-542812D01*
X490010Y-542562D01*
X490063Y-542271D01*
X490010Y-541979D01*
X489850Y-541729D01*
X489663Y-541646D01*
X488837D01*
G01X455550Y-516979D02*
Y-521979D01*
G01X454093Y-516979D02*
X457007D01*
G01X460650Y-521979D02*
X460270Y-521896D01*
X459890Y-521562D01*
X459637Y-520979D01*
X459510Y-520312D01*
X459637Y-519646D01*
X459890Y-519062D01*
X460270Y-518729D01*
X460650Y-518646D01*
X461030Y-518729D01*
X461410Y-519062D01*
X461663Y-519646D01*
X461727Y-520312D01*
X461663Y-520979D01*
X461410Y-521562D01*
X461030Y-521896D01*
X460650Y-521979D01*
G01X465750D02*
X465370Y-521896D01*
X464990Y-521562D01*
X464737Y-520979D01*
X464610Y-520312D01*
X464737Y-519646D01*
X464990Y-519062D01*
X465370Y-518729D01*
X465750Y-518646D01*
X466130Y-518729D01*
X466510Y-519062D01*
X466763Y-519646D01*
X466827Y-520312D01*
X466763Y-520979D01*
X466510Y-521562D01*
X466130Y-521896D01*
X465750Y-521979D01*
G01X470850D02*
Y-516979D01*
G01X475950Y-522146D02*
X475823Y-522062D01*
Y-521896D01*
X475950Y-521812D01*
X476077Y-521896D01*
Y-522062D01*
X475950Y-522146D01*
G01Y-519896D02*
X475823Y-519812D01*
Y-519646D01*
X475950Y-519562D01*
X476077Y-519646D01*
Y-519812D01*
X475950Y-519896D01*
G01X454283Y-496979D02*
Y-491979D01*
X455867D01*
X456373Y-492229D01*
X456690Y-492562D01*
X456817Y-493229D01*
X456690Y-493896D01*
X456310Y-494312D01*
X455867Y-494562D01*
X454283D01*
G01X455867D02*
X456817Y-496979D01*
G01X461917D02*
X459383D01*
Y-491979D01*
X461917D01*
G01X460903Y-494396D02*
X459383D01*
G01X464167Y-491979D02*
X465750Y-496979D01*
X467333Y-491979D01*
G01X470850Y-497146D02*
X470723Y-497062D01*
Y-496896D01*
X470850Y-496812D01*
X470977Y-496896D01*
Y-497062D01*
X470850Y-497146D01*
G01Y-494896D02*
X470723Y-494812D01*
Y-494646D01*
X470850Y-494562D01*
X470977Y-494646D01*
Y-494812D01*
X470850Y-494896D01*
G01X-984580Y-698988D02*
Y4193602D01*
X5868320D01*
Y-698988D01*
X-984580D01*
G01X7723Y-521204D02*
X7253Y-520889D01*
X6705Y-520679D01*
X6078D01*
X5373Y-520994D01*
X4825Y-521519D01*
X4433Y-522149D01*
X4120Y-523199D01*
X4042Y-524144D01*
X4198Y-525089D01*
X4433Y-525719D01*
X4903Y-526349D01*
X5452Y-526769D01*
X6000Y-526979D01*
X6548D01*
X7097Y-526769D01*
X7567Y-526454D01*
X7958Y-526034D01*
G01X11360Y-520679D02*
X13240D01*
G01X12300D02*
Y-526979D01*
G01X11360D02*
X13240D01*
G01X18600Y-520679D02*
Y-526979D01*
G01X16798Y-520679D02*
X20402D01*
G01X24900Y-526979D02*
Y-524144D01*
X23333Y-520679D01*
G01X26467D02*
X24900Y-524144D01*
G01X35777Y-525719D02*
X36247Y-526454D01*
X36873Y-526874D01*
X37578Y-526979D01*
X38205Y-526874D01*
X38832Y-526349D01*
X39223Y-525719D01*
X39302Y-525089D01*
X39145Y-524354D01*
X38597Y-523829D01*
X38048Y-523619D01*
X37343D01*
G01X38048D02*
X38518Y-523304D01*
X38910Y-522779D01*
X39067Y-522149D01*
X38910Y-521519D01*
X38518Y-520994D01*
X37813Y-520679D01*
X37108Y-520784D01*
X36403Y-521204D01*
G01X42077Y-525719D02*
X42547Y-526454D01*
X43173Y-526874D01*
X43878Y-526979D01*
X44505Y-526874D01*
X45132Y-526349D01*
X45523Y-525719D01*
X45602Y-525089D01*
X45445Y-524354D01*
X44897Y-523829D01*
X44348Y-523619D01*
X43643D01*
G01X44348D02*
X44818Y-523304D01*
X45210Y-522779D01*
X45367Y-522149D01*
X45210Y-521519D01*
X44818Y-520994D01*
X44113Y-520679D01*
X43408Y-520784D01*
X42703Y-521204D01*
G01X48377Y-525719D02*
X48847Y-526454D01*
X49473Y-526874D01*
X50178Y-526979D01*
X50805Y-526874D01*
X51432Y-526349D01*
X51823Y-525719D01*
X51902Y-525089D01*
X51745Y-524354D01*
X51197Y-523829D01*
X50648Y-523619D01*
X49943D01*
G01X50648D02*
X51118Y-523304D01*
X51510Y-522779D01*
X51667Y-522149D01*
X51510Y-521519D01*
X51118Y-520994D01*
X50413Y-520679D01*
X49708Y-520784D01*
X49003Y-521204D01*
G01X56243Y-526979D02*
X56400Y-525614D01*
X56635Y-524459D01*
X56948Y-523409D01*
X57340Y-522254D01*
X57967Y-520679D01*
X54833D01*
G01X62543Y-526979D02*
X62700Y-525614D01*
X62935Y-524459D01*
X63248Y-523409D01*
X63640Y-522254D01*
X64267Y-520679D01*
X61133D01*
G01X68843Y-528134D02*
X69157Y-526769D01*
G01X75300Y-520679D02*
Y-526979D01*
G01X73498Y-520679D02*
X77102D01*
G01X79642Y-526979D02*
X81600Y-520679D01*
X83558Y-526979D01*
G01X82853Y-524774D02*
X80347D01*
G01X86960Y-520679D02*
X88840D01*
G01X87900D02*
Y-526979D01*
G01X86960D02*
X88840D01*
G01X91850Y-520679D02*
X92947Y-526979D01*
X94200Y-520679D01*
X95453Y-526979D01*
X96550Y-520679D01*
G01X98542Y-526979D02*
X100500Y-520679D01*
X102458Y-526979D01*
G01X101753Y-524774D02*
X99247D01*
G01X104998Y-526979D02*
Y-520679D01*
X108602Y-526979D01*
Y-520679D01*
G01X119008Y-529079D02*
X118225Y-528029D01*
X117833Y-526979D01*
Y-522779D01*
X118225Y-521729D01*
X119008Y-520679D01*
G01X130433Y-526979D02*
Y-520679D01*
X132392D01*
X133018Y-520994D01*
X133410Y-521414D01*
X133567Y-522254D01*
X133410Y-523094D01*
X132940Y-523619D01*
X132392Y-523934D01*
X130433D01*
G01X132392D02*
X133567Y-526979D01*
G01X138300Y-527189D02*
X138143Y-527084D01*
Y-526874D01*
X138300Y-526769D01*
X138457Y-526874D01*
Y-527084D01*
X138300Y-527189D01*
G01X144600Y-526979D02*
X143973Y-526874D01*
X143425Y-526454D01*
X142955Y-525824D01*
X142642Y-525089D01*
X142485Y-524249D01*
Y-523409D01*
X142642Y-522569D01*
X142955Y-521834D01*
X143425Y-521204D01*
X143973Y-520784D01*
X144600Y-520679D01*
X145227Y-520784D01*
X145775Y-521204D01*
X146245Y-521834D01*
X146558Y-522569D01*
X146715Y-523409D01*
Y-524249D01*
X146558Y-525089D01*
X146245Y-525824D01*
X145775Y-526454D01*
X145227Y-526874D01*
X144600Y-526979D01*
G01X150900Y-527189D02*
X150743Y-527084D01*
Y-526874D01*
X150900Y-526769D01*
X151057Y-526874D01*
Y-527084D01*
X150900Y-527189D01*
G01X158923Y-521204D02*
X158453Y-520889D01*
X157905Y-520679D01*
X157278D01*
X156573Y-520994D01*
X156025Y-521519D01*
X155633Y-522149D01*
X155320Y-523199D01*
X155242Y-524144D01*
X155398Y-525089D01*
X155633Y-525719D01*
X156103Y-526349D01*
X156652Y-526769D01*
X157200Y-526979D01*
X157748D01*
X158297Y-526769D01*
X158767Y-526454D01*
X159158Y-526034D01*
G01X163500Y-527189D02*
X163343Y-527084D01*
Y-526874D01*
X163500Y-526769D01*
X163657Y-526874D01*
Y-527084D01*
X163500Y-527189D01*
G01X170192Y-529079D02*
X170975Y-528029D01*
X171367Y-526979D01*
Y-522779D01*
X170975Y-521729D01*
X170192Y-520679D01*
G01X6470Y-513829D02*
X8037D01*
Y-515719D01*
X7567Y-516349D01*
X7018Y-516769D01*
X6235Y-516979D01*
X5452Y-516769D01*
X4903Y-516349D01*
X4433Y-515719D01*
X4120Y-514984D01*
X3963Y-514144D01*
Y-513409D01*
X4120Y-512779D01*
X4433Y-512044D01*
X4903Y-511414D01*
X5373Y-510994D01*
X6000Y-510679D01*
X6548D01*
X7175Y-510889D01*
X7645Y-511309D01*
G01X10577Y-510679D02*
Y-515194D01*
X10890Y-516139D01*
X11517Y-516769D01*
X12300Y-516979D01*
X13083Y-516769D01*
X13710Y-516139D01*
X14023Y-515194D01*
Y-510679D01*
G01X17660D02*
X19540D01*
G01X18600D02*
Y-516979D01*
G01X17660D02*
X19540D01*
G01X23255Y-516139D02*
X23882Y-516664D01*
X24587Y-516979D01*
X25213D01*
X25840Y-516664D01*
X26310Y-516139D01*
X26545Y-515404D01*
X26388Y-514669D01*
X25997Y-514039D01*
X25292Y-513619D01*
X24352Y-513409D01*
X23803Y-512989D01*
X23568Y-512254D01*
X23725Y-511519D01*
X24117Y-510994D01*
X24665Y-510679D01*
X25213D01*
X25762Y-510889D01*
X26232Y-511414D01*
G01X29555Y-516979D02*
Y-510679D01*
G01X32845D02*
Y-516979D01*
G01Y-513829D02*
X29555D01*
G01X35542Y-516979D02*
X37500Y-510679D01*
X39458Y-516979D01*
G01X38753Y-514774D02*
X36247D01*
G01X41998Y-516979D02*
Y-510679D01*
X45602Y-516979D01*
Y-510679D01*
G01X54677Y-516979D02*
Y-510679D01*
X56243D01*
X56870Y-510994D01*
X57340Y-511414D01*
X57732Y-512044D01*
X58045Y-512779D01*
X58123Y-513829D01*
X58045Y-514879D01*
X57732Y-515614D01*
X57340Y-516244D01*
X56870Y-516664D01*
X56243Y-516979D01*
X54677D01*
G01X61760Y-510679D02*
X63640D01*
G01X62700D02*
Y-516979D01*
G01X61760D02*
X63640D01*
G01X67355Y-516139D02*
X67982Y-516664D01*
X68687Y-516979D01*
X69313D01*
X69940Y-516664D01*
X70410Y-516139D01*
X70645Y-515404D01*
X70488Y-514669D01*
X70097Y-514039D01*
X69392Y-513619D01*
X68452Y-513409D01*
X67903Y-512989D01*
X67668Y-512254D01*
X67825Y-511519D01*
X68217Y-510994D01*
X68765Y-510679D01*
X69313D01*
X69862Y-510889D01*
X70332Y-511414D01*
G01X75300Y-510679D02*
Y-516979D01*
G01X73498Y-510679D02*
X77102D01*
G01X81600Y-517189D02*
X81443Y-517084D01*
Y-516874D01*
X81600Y-516769D01*
X81757Y-516874D01*
Y-517084D01*
X81600Y-517189D01*
G01X87743Y-518134D02*
X88057Y-516769D01*
G01X94200Y-510679D02*
Y-516979D01*
G01X92398Y-510679D02*
X96002D01*
G01X98542Y-516979D02*
X100500Y-510679D01*
X102458Y-516979D01*
G01X101753Y-514774D02*
X99247D01*
G01X106800Y-516979D02*
X106173Y-516874D01*
X105625Y-516454D01*
X105155Y-515824D01*
X104842Y-515089D01*
X104685Y-514249D01*
Y-513409D01*
X104842Y-512569D01*
X105155Y-511834D01*
X105625Y-511204D01*
X106173Y-510784D01*
X106800Y-510679D01*
X107427Y-510784D01*
X107975Y-511204D01*
X108445Y-511834D01*
X108758Y-512569D01*
X108915Y-513409D01*
Y-514249D01*
X108758Y-515089D01*
X108445Y-515824D01*
X107975Y-516454D01*
X107427Y-516874D01*
X106800Y-516979D01*
G01X113100D02*
Y-514144D01*
X111533Y-510679D01*
G01X114667D02*
X113100Y-514144D01*
G01X117677Y-510679D02*
Y-515194D01*
X117990Y-516139D01*
X118617Y-516769D01*
X119400Y-516979D01*
X120183Y-516769D01*
X120810Y-516139D01*
X121123Y-515194D01*
Y-510679D01*
G01X123742Y-516979D02*
X125700Y-510679D01*
X127658Y-516979D01*
G01X126953Y-514774D02*
X124447D01*
G01X130198Y-516979D02*
Y-510679D01*
X133802Y-516979D01*
Y-510679D01*
G01X4198Y-506979D02*
Y-500679D01*
X7802Y-506979D01*
Y-500679D01*
G01X12300Y-506979D02*
X11673Y-506874D01*
X11125Y-506454D01*
X10655Y-505824D01*
X10342Y-505089D01*
X10185Y-504249D01*
Y-503409D01*
X10342Y-502569D01*
X10655Y-501834D01*
X11125Y-501204D01*
X11673Y-500784D01*
X12300Y-500679D01*
X12927Y-500784D01*
X13475Y-501204D01*
X13945Y-501834D01*
X14258Y-502569D01*
X14415Y-503409D01*
Y-504249D01*
X14258Y-505089D01*
X13945Y-505824D01*
X13475Y-506454D01*
X12927Y-506874D01*
X12300Y-506979D01*
G01X18600Y-507189D02*
X18443Y-507084D01*
Y-506874D01*
X18600Y-506769D01*
X18757Y-506874D01*
Y-507084D01*
X18600Y-507189D01*
G01X23412Y-501729D02*
X23882Y-501099D01*
X24430Y-500784D01*
X25057Y-500679D01*
X25840Y-500889D01*
X26388Y-501414D01*
X26545Y-502044D01*
X26467Y-502674D01*
X26153Y-503199D01*
X24587Y-504249D01*
X23882Y-504984D01*
X23412Y-506034D01*
X23255Y-506979D01*
X26545D01*
G01X31200D02*
Y-500679D01*
X30260Y-501939D01*
G01Y-506979D02*
X32140D01*
G01X37500D02*
Y-500679D01*
X36560Y-501939D01*
G01Y-506979D02*
X38440D01*
G01X43643Y-508134D02*
X43957Y-506769D01*
G01X47750Y-500679D02*
X48847Y-506979D01*
X50100Y-500679D01*
X51353Y-506979D01*
X52450Y-500679D01*
G01X57967Y-506979D02*
X54833D01*
Y-500679D01*
X57967D01*
G01X56713Y-503724D02*
X54833D01*
G01X60898Y-506979D02*
Y-500679D01*
X64502Y-506979D01*
Y-500679D01*
G01X67355Y-506979D02*
Y-500679D01*
G01X70645D02*
Y-506979D01*
G01Y-503829D02*
X67355D01*
G01X73577Y-500679D02*
Y-505194D01*
X73890Y-506139D01*
X74517Y-506769D01*
X75300Y-506979D01*
X76083Y-506769D01*
X76710Y-506139D01*
X77023Y-505194D01*
Y-500679D01*
G01X79642Y-506979D02*
X81600Y-500679D01*
X83558Y-506979D01*
G01X82853Y-504774D02*
X80347D01*
G01X92712Y-501729D02*
X93182Y-501099D01*
X93730Y-500784D01*
X94357Y-500679D01*
X95140Y-500889D01*
X95688Y-501414D01*
X95845Y-502044D01*
X95767Y-502674D01*
X95453Y-503199D01*
X93887Y-504249D01*
X93182Y-504984D01*
X92712Y-506034D01*
X92555Y-506979D01*
X95845D01*
G01X98698D02*
Y-500679D01*
X102302Y-506979D01*
Y-500679D01*
G01X105077Y-506979D02*
Y-500679D01*
X106643D01*
X107270Y-500994D01*
X107740Y-501414D01*
X108132Y-502044D01*
X108445Y-502779D01*
X108523Y-503829D01*
X108445Y-504879D01*
X108132Y-505614D01*
X107740Y-506244D01*
X107270Y-506664D01*
X106643Y-506979D01*
X105077D01*
G01X117833D02*
Y-500679D01*
X119792D01*
X120418Y-500994D01*
X120810Y-501414D01*
X120967Y-502254D01*
X120810Y-503094D01*
X120340Y-503619D01*
X119792Y-503934D01*
X117833D01*
G01X119792D02*
X120967Y-506979D01*
G01X123977D02*
Y-500679D01*
X125543D01*
X126170Y-500994D01*
X126640Y-501414D01*
X127032Y-502044D01*
X127345Y-502779D01*
X127423Y-503829D01*
X127345Y-504879D01*
X127032Y-505614D01*
X126640Y-506244D01*
X126170Y-506664D01*
X125543Y-506979D01*
X123977D01*
G01X132000Y-507189D02*
X131843Y-507084D01*
Y-506874D01*
X132000Y-506769D01*
X132157Y-506874D01*
Y-507084D01*
X132000Y-507189D01*
G01X28300Y-494279D02*
X25780Y-493862D01*
X23575Y-492196D01*
X21685Y-489696D01*
X20425Y-486779D01*
X19795Y-483446D01*
Y-480112D01*
X20425Y-476779D01*
X21685Y-473862D01*
X23575Y-471363D01*
X25780Y-469696D01*
X28300Y-469279D01*
X30820Y-469696D01*
X33025Y-471363D01*
X34915Y-473862D01*
X36175Y-476779D01*
X36805Y-480112D01*
Y-483446D01*
X36175Y-486779D01*
X34915Y-489696D01*
X33025Y-492196D01*
X30820Y-493862D01*
X28300Y-494279D01*
G01X30820Y-487612D02*
X34600Y-494279D01*
G01X48145Y-477613D02*
Y-489279D01*
X49405Y-492196D01*
X51295Y-493862D01*
X53500Y-494279D01*
X55705Y-493862D01*
X57595Y-492196D01*
X58855Y-489279D01*
G01Y-494279D02*
Y-477613D01*
G01X84370Y-494279D02*
Y-477613D01*
G01Y-480529D02*
X83110Y-478863D01*
X81220Y-478029D01*
X79015Y-477613D01*
X76810Y-478446D01*
X74920Y-480112D01*
X73660Y-482613D01*
X73030Y-485946D01*
X73660Y-489279D01*
X74920Y-491780D01*
X76810Y-493446D01*
X79015Y-494279D01*
X81220Y-493862D01*
X83110Y-492613D01*
X84370Y-490946D01*
G01X98545Y-494279D02*
Y-477613D01*
G01Y-481779D02*
X99805Y-479696D01*
X101695Y-478029D01*
X104215Y-477613D01*
X106420Y-478029D01*
X108310Y-479696D01*
X109255Y-482613D01*
Y-494279D01*
G01X129100Y-469279D02*
Y-494279D01*
G01X124690Y-477613D02*
X133510D01*
G01X159970Y-494279D02*
Y-477613D01*
G01Y-480529D02*
X158710Y-478863D01*
X156820Y-478029D01*
X154615Y-477613D01*
X152410Y-478446D01*
X150520Y-480112D01*
X149260Y-482613D01*
X148630Y-485946D01*
X149260Y-489279D01*
X150520Y-491780D01*
X152410Y-493446D01*
X154615Y-494279D01*
X156820Y-493862D01*
X158710Y-492613D01*
X159970Y-490946D01*
G01X206579Y-508436D02*
Y-500436D01*
X209179Y-507103D01*
X211779Y-500436D01*
Y-508436D01*
G01X214679D02*
X217179Y-500436D01*
X219679Y-508436D01*
G01X218779Y-505636D02*
X215579D01*
G01X223079Y-507370D02*
X223879Y-508036D01*
X224779Y-508436D01*
X225579D01*
X226379Y-508036D01*
X226979Y-507370D01*
X227279Y-506436D01*
X227079Y-505503D01*
X226579Y-504703D01*
X225679Y-504169D01*
X224479Y-503903D01*
X223779Y-503369D01*
X223479Y-502436D01*
X223679Y-501503D01*
X224179Y-500836D01*
X224879Y-500436D01*
X225579D01*
X226279Y-500703D01*
X226879Y-501369D01*
G01X230979Y-508436D02*
Y-500436D01*
G01X234779D02*
X230979Y-505370D01*
G01X235379Y-508436D02*
X232679Y-503103D01*
G01X239879Y-505769D02*
X242479D01*
G01X249979Y-504169D02*
X250379Y-503769D01*
X250679Y-503103D01*
X250879Y-502169D01*
X250679Y-501369D01*
X250279Y-500836D01*
X249579Y-500436D01*
X246879D01*
Y-508436D01*
X250179D01*
X250879Y-507903D01*
X251279Y-507103D01*
X251479Y-506169D01*
X251279Y-505236D01*
X250679Y-504436D01*
X249979Y-504169D01*
X246879D01*
G01X257179Y-508436D02*
X256379Y-508303D01*
X255679Y-507769D01*
X255079Y-506969D01*
X254679Y-506036D01*
X254479Y-504969D01*
Y-503903D01*
X254679Y-502836D01*
X255079Y-501903D01*
X255679Y-501103D01*
X256379Y-500569D01*
X257179Y-500436D01*
X257979Y-500569D01*
X258679Y-501103D01*
X259279Y-501903D01*
X259679Y-502836D01*
X259879Y-503903D01*
Y-504969D01*
X259679Y-506036D01*
X259279Y-506969D01*
X258679Y-507769D01*
X257979Y-508303D01*
X257179Y-508436D01*
G01X265179Y-500436D02*
Y-508436D01*
G01X262879Y-500436D02*
X267479D01*
G01X199650Y-473979D02*
Y-481979D01*
X203650D01*
G01X211450D02*
Y-476646D01*
G01Y-477579D02*
X211050Y-477046D01*
X210450Y-476779D01*
X209750Y-476646D01*
X209050Y-476912D01*
X208450Y-477446D01*
X208050Y-478246D01*
X207850Y-479312D01*
X208050Y-480379D01*
X208450Y-481179D01*
X209050Y-481712D01*
X209750Y-481979D01*
X210450Y-481846D01*
X211050Y-481446D01*
X211450Y-480913D01*
G01X215550Y-484379D02*
X216150Y-484646D01*
X216950Y-484379D01*
X217450Y-483846D01*
X217850Y-483179D01*
X218450Y-481046D01*
X219750Y-476646D01*
G01X216550D02*
X218450Y-481046D01*
G01X224150Y-478379D02*
X227350D01*
X227050Y-477446D01*
X226550Y-476912D01*
X225850Y-476646D01*
X225150Y-476779D01*
X224550Y-477179D01*
X224150Y-478112D01*
X223950Y-478913D01*
Y-479712D01*
X224150Y-480512D01*
X224650Y-481312D01*
X225250Y-481846D01*
X225950Y-481979D01*
X226650Y-481712D01*
X227350Y-480913D01*
G01X232250Y-481979D02*
Y-476646D01*
G01Y-477712D02*
X232750Y-477179D01*
X233250Y-476779D01*
X233950Y-476646D01*
X234450Y-476779D01*
X235050Y-477179D01*
G01X223350Y-531979D02*
Y-523979D01*
X227950Y-531979D01*
Y-523979D01*
G01X233650Y-526646D02*
Y-531979D01*
G01Y-524512D02*
X233450Y-524379D01*
Y-524112D01*
X233650Y-523979D01*
X233850Y-524112D01*
Y-524379D01*
X233650Y-524512D01*
G01X239950Y-531979D02*
Y-526646D01*
G01Y-527979D02*
X240350Y-527312D01*
X240950Y-526779D01*
X241750Y-526646D01*
X242450Y-526779D01*
X243050Y-527312D01*
X243350Y-528246D01*
Y-531979D01*
G01X251450D02*
Y-526646D01*
G01Y-527579D02*
X251050Y-527046D01*
X250450Y-526779D01*
X249750Y-526646D01*
X249050Y-526912D01*
X248450Y-527446D01*
X248050Y-528246D01*
X247850Y-529312D01*
X248050Y-530379D01*
X248450Y-531179D01*
X249050Y-531712D01*
X249750Y-531979D01*
X250450Y-531846D01*
X251050Y-531446D01*
X251450Y-530913D01*
G01X326250Y-525312D02*
X326850Y-524512D01*
X327550Y-524112D01*
X328350Y-523979D01*
X329350Y-524246D01*
X330050Y-524912D01*
X330250Y-525712D01*
X330150Y-526513D01*
X329750Y-527179D01*
X327750Y-528512D01*
X326850Y-529446D01*
X326250Y-530779D01*
X326050Y-531979D01*
X330250D01*
G01X336150Y-523979D02*
X335350Y-524246D01*
X334750Y-524912D01*
X334350Y-525712D01*
X334050Y-526779D01*
X333950Y-527979D01*
X334050Y-529179D01*
X334350Y-530246D01*
X334750Y-531046D01*
X335350Y-531712D01*
X336150Y-531979D01*
X336950Y-531712D01*
X337550Y-531046D01*
X337950Y-530246D01*
X338250Y-529179D01*
X338350Y-527979D01*
X338250Y-526779D01*
X337950Y-525712D01*
X337550Y-524912D01*
X336950Y-524246D01*
X336150Y-523979D01*
G01X342250Y-525312D02*
X342850Y-524512D01*
X343550Y-524112D01*
X344350Y-523979D01*
X345350Y-524246D01*
X346050Y-524912D01*
X346250Y-525712D01*
X346150Y-526513D01*
X345750Y-527179D01*
X343750Y-528512D01*
X342850Y-529446D01*
X342250Y-530779D01*
X342050Y-531979D01*
X346250D01*
G01X349950Y-530379D02*
X350550Y-531312D01*
X351350Y-531846D01*
X352250Y-531979D01*
X353050Y-531846D01*
X353850Y-531179D01*
X354350Y-530379D01*
X354450Y-529579D01*
X354250Y-528646D01*
X353550Y-527979D01*
X352850Y-527712D01*
X351950D01*
G01X352850D02*
X353450Y-527312D01*
X353950Y-526646D01*
X354150Y-525846D01*
X353950Y-525046D01*
X353450Y-524379D01*
X352550Y-523979D01*
X351650Y-524112D01*
X350750Y-524646D01*
G01X358350Y-532246D02*
X361950Y-523979D01*
G01X368150D02*
X367350Y-524246D01*
X366750Y-524912D01*
X366350Y-525712D01*
X366050Y-526779D01*
X365950Y-527979D01*
X366050Y-529179D01*
X366350Y-530246D01*
X366750Y-531046D01*
X367350Y-531712D01*
X368150Y-531979D01*
X368950Y-531712D01*
X369550Y-531046D01*
X369950Y-530246D01*
X370250Y-529179D01*
X370350Y-527979D01*
X370250Y-526779D01*
X369950Y-525712D01*
X369550Y-524912D01*
X368950Y-524246D01*
X368150Y-523979D01*
G01X373950Y-530379D02*
X374550Y-531312D01*
X375350Y-531846D01*
X376250Y-531979D01*
X377050Y-531846D01*
X377850Y-531179D01*
X378350Y-530379D01*
X378450Y-529579D01*
X378250Y-528646D01*
X377550Y-527979D01*
X376850Y-527712D01*
X375950D01*
G01X376850D02*
X377450Y-527312D01*
X377950Y-526646D01*
X378150Y-525846D01*
X377950Y-525046D01*
X377450Y-524379D01*
X376550Y-523979D01*
X375650Y-524112D01*
X374750Y-524646D01*
G01X382350Y-532246D02*
X385950Y-523979D01*
G01X390250Y-525312D02*
X390850Y-524512D01*
X391550Y-524112D01*
X392350Y-523979D01*
X393350Y-524246D01*
X394050Y-524912D01*
X394250Y-525712D01*
X394150Y-526513D01*
X393750Y-527179D01*
X391750Y-528512D01*
X390850Y-529446D01*
X390250Y-530779D01*
X390050Y-531979D01*
X394250D01*
G01X401350D02*
Y-523979D01*
X397650Y-529712D01*
X402650D01*
G01X325950Y-506979D02*
Y-498979D01*
X327950D01*
X328750Y-499379D01*
X329350Y-499912D01*
X329850Y-500712D01*
X330250Y-501646D01*
X330350Y-502979D01*
X330250Y-504312D01*
X329850Y-505246D01*
X329350Y-506046D01*
X328750Y-506579D01*
X327950Y-506979D01*
X325950D01*
G01X333650D02*
X336150Y-498979D01*
X338650Y-506979D01*
G01X337750Y-504179D02*
X334550D01*
G01X344150Y-498979D02*
X343350Y-499246D01*
X342750Y-499912D01*
X342350Y-500712D01*
X342050Y-501779D01*
X341950Y-502979D01*
X342050Y-504179D01*
X342350Y-505246D01*
X342750Y-506046D01*
X343350Y-506712D01*
X344150Y-506979D01*
X344950Y-506712D01*
X345550Y-506046D01*
X345950Y-505246D01*
X346250Y-504179D01*
X346350Y-502979D01*
X346250Y-501779D01*
X345950Y-500712D01*
X345550Y-499912D01*
X344950Y-499246D01*
X344150Y-498979D01*
G01X350250Y-506979D02*
Y-498979D01*
X354050D01*
G01X352650Y-502846D02*
X350250D01*
G01X360150Y-498979D02*
X359350Y-499246D01*
X358750Y-499912D01*
X358350Y-500712D01*
X358050Y-501779D01*
X357950Y-502979D01*
X358050Y-504179D01*
X358350Y-505246D01*
X358750Y-506046D01*
X359350Y-506712D01*
X360150Y-506979D01*
X360950Y-506712D01*
X361550Y-506046D01*
X361950Y-505246D01*
X362250Y-504179D01*
X362350Y-502979D01*
X362250Y-501779D01*
X361950Y-500712D01*
X361550Y-499912D01*
X360950Y-499246D01*
X360150Y-498979D01*
G01X368150D02*
Y-506979D01*
G01X365850Y-498979D02*
X370450D01*
G01X373550Y-506979D02*
Y-498979D01*
X376150Y-505646D01*
X378750Y-498979D01*
Y-506979D01*
G01X384950Y-502712D02*
X385350Y-502312D01*
X385650Y-501646D01*
X385850Y-500712D01*
X385650Y-499912D01*
X385250Y-499379D01*
X384550Y-498979D01*
X381850D01*
Y-506979D01*
X385150D01*
X385850Y-506446D01*
X386250Y-505646D01*
X386450Y-504712D01*
X386250Y-503779D01*
X385650Y-502979D01*
X384950Y-502712D01*
X381850D01*
G01X390950Y-498979D02*
X393350D01*
G01X392150D02*
Y-506979D01*
G01X390950D02*
X393350D01*
G01X398150Y-505379D02*
X398650Y-506179D01*
X399250Y-506712D01*
X399950Y-506979D01*
X400750Y-506712D01*
X401350Y-506179D01*
X401950Y-505379D01*
X402150Y-504312D01*
Y-498979D01*
G01X408150D02*
X407350Y-499246D01*
X406750Y-499912D01*
X406350Y-500712D01*
X406050Y-501779D01*
X405950Y-502979D01*
X406050Y-504179D01*
X406350Y-505246D01*
X406750Y-506046D01*
X407350Y-506712D01*
X408150Y-506979D01*
X408950Y-506712D01*
X409550Y-506046D01*
X409950Y-505246D01*
X410250Y-504179D01*
X410350Y-502979D01*
X410250Y-501779D01*
X409950Y-500712D01*
X409550Y-499912D01*
X408950Y-499246D01*
X408150Y-498979D01*
G01X343750Y-481979D02*
Y-473979D01*
X347550D01*
G01X346150Y-477846D02*
X343750D01*
G01X353650Y-473979D02*
X352850Y-474246D01*
X352250Y-474912D01*
X351850Y-475712D01*
X351550Y-476779D01*
X351450Y-477979D01*
X351550Y-479179D01*
X351850Y-480246D01*
X352250Y-481046D01*
X352850Y-481712D01*
X353650Y-481979D01*
X354450Y-481712D01*
X355050Y-481046D01*
X355450Y-480246D01*
X355750Y-479179D01*
X355850Y-477979D01*
X355750Y-476779D01*
X355450Y-475712D01*
X355050Y-474912D01*
X354450Y-474246D01*
X353650Y-473979D01*
G01X361650D02*
Y-481979D01*
G01X359350Y-473979D02*
X363950D01*
G01X366650Y-484646D02*
X372650D01*
G01X375050Y-481979D02*
Y-473979D01*
X377650Y-480646D01*
X380250Y-473979D01*
Y-481979D01*
G01X386450Y-477712D02*
X386850Y-477312D01*
X387150Y-476646D01*
X387350Y-475712D01*
X387150Y-474912D01*
X386750Y-474379D01*
X386050Y-473979D01*
X383350D01*
Y-481979D01*
X386650D01*
X387350Y-481446D01*
X387750Y-480646D01*
X387950Y-479712D01*
X387750Y-478779D01*
X387150Y-477979D01*
X386450Y-477712D01*
X383350D01*
G01X390650Y-484646D02*
X396650D01*
G01X403650Y-481979D02*
X399650D01*
Y-473979D01*
X403650D01*
G01X402050Y-477846D02*
X399650D01*
G01X407050Y-481979D02*
Y-473979D01*
X409650Y-480646D01*
X412250Y-473979D01*
Y-481979D01*
G01X417650D02*
X418350Y-481846D01*
X419150Y-481446D01*
X419650Y-480779D01*
X419850Y-479846D01*
X419650Y-478913D01*
X419050Y-478112D01*
X418150Y-477712D01*
X417150D01*
X416550Y-477446D01*
X416050Y-476779D01*
X415850Y-475846D01*
X416150Y-474912D01*
X416850Y-474246D01*
X417650Y-473979D01*
X418450Y-474246D01*
X419150Y-474912D01*
X419450Y-475846D01*
X419250Y-476779D01*
X418750Y-477446D01*
X418150Y-477712D01*
X417150D01*
X416250Y-478112D01*
X415650Y-478913D01*
X415450Y-479846D01*
X415650Y-480779D01*
X416150Y-481446D01*
X416950Y-481846D01*
X417650Y-481979D01*
G01X423950Y-481046D02*
X424650Y-481712D01*
X425450Y-481979D01*
X426250Y-481712D01*
X426950Y-480913D01*
X427450Y-479712D01*
X427650Y-478512D01*
Y-477046D01*
X427450Y-475846D01*
X426950Y-474779D01*
X426350Y-474246D01*
X425650Y-473979D01*
X424850Y-474246D01*
X424250Y-474779D01*
X423850Y-475579D01*
X423650Y-476646D01*
X423850Y-477579D01*
X424350Y-478512D01*
X424950Y-479046D01*
X425650Y-479179D01*
X426450Y-478913D01*
X427050Y-478246D01*
X427650Y-477046D01*
G01X433650Y-473979D02*
X432850Y-474246D01*
X432250Y-474912D01*
X431850Y-475712D01*
X431550Y-476779D01*
X431450Y-477979D01*
X431550Y-479179D01*
X431850Y-480246D01*
X432250Y-481046D01*
X432850Y-481712D01*
X433650Y-481979D01*
X434450Y-481712D01*
X435050Y-481046D01*
X435450Y-480246D01*
X435750Y-479179D01*
X435850Y-477979D01*
X435750Y-476779D01*
X435450Y-475712D01*
X435050Y-474912D01*
X434450Y-474246D01*
X433650Y-473979D01*
G01X439450Y-481979D02*
Y-473979D01*
G01X443250D02*
X439450Y-478913D01*
G01X443850Y-481979D02*
X441150Y-476646D01*
G01X414650Y-534979D02*
Y-526979D01*
X413450Y-528579D01*
G01Y-534979D02*
X415850D01*
G01X420750Y-531646D02*
X421450Y-530712D01*
X422050Y-530179D01*
X422850Y-529912D01*
X423550Y-530179D01*
X424050Y-530712D01*
X424450Y-531512D01*
X424550Y-532446D01*
X424450Y-533246D01*
X424050Y-534046D01*
X423450Y-534712D01*
X422750Y-534979D01*
X421950Y-534712D01*
X421250Y-533913D01*
X420850Y-532712D01*
X420750Y-531379D01*
X420950Y-529646D01*
X421250Y-528712D01*
X421750Y-527779D01*
X422450Y-527112D01*
X423150Y-526979D01*
X423850Y-527246D01*
X424350Y-527912D01*
G01X430650Y-535246D02*
X430450Y-535112D01*
Y-534846D01*
X430650Y-534712D01*
X430850Y-534846D01*
Y-535112D01*
X430650Y-535246D01*
G01X436750Y-531646D02*
X437450Y-530712D01*
X438050Y-530179D01*
X438850Y-529912D01*
X439550Y-530179D01*
X440050Y-530712D01*
X440450Y-531512D01*
X440550Y-532446D01*
X440450Y-533246D01*
X440050Y-534046D01*
X439450Y-534712D01*
X438750Y-534979D01*
X437950Y-534712D01*
X437250Y-533913D01*
X436850Y-532712D01*
X436750Y-531379D01*
X436950Y-529646D01*
X437250Y-528712D01*
X437750Y-527779D01*
X438450Y-527112D01*
X439150Y-526979D01*
X439850Y-527246D01*
X440350Y-527912D01*
G01X459650Y-534979D02*
Y-526979D01*
X458450Y-528579D01*
G01Y-534979D02*
X460850D01*
G01X467450D02*
X467650Y-533246D01*
X467950Y-531779D01*
X468350Y-530446D01*
X468850Y-528979D01*
X469650Y-526979D01*
X465650D01*
G01X475650Y-535246D02*
X475450Y-535112D01*
Y-534846D01*
X475650Y-534712D01*
X475850Y-534846D01*
Y-535112D01*
X475650Y-535246D01*
G01X481750Y-528312D02*
X482350Y-527512D01*
X483050Y-527112D01*
X483850Y-526979D01*
X484850Y-527246D01*
X485550Y-527912D01*
X485750Y-528712D01*
X485650Y-529513D01*
X485250Y-530179D01*
X483250Y-531512D01*
X482350Y-532446D01*
X481750Y-533779D01*
X481550Y-534979D01*
X485750D01*
G01X479650Y-508379D02*
X480150Y-509179D01*
X480750Y-509712D01*
X481450Y-509979D01*
X482250Y-509712D01*
X482850Y-509179D01*
X483450Y-508379D01*
X483650Y-507312D01*
Y-501979D01*
G54D70*
X717110Y-21500D03*
X834070Y8500D03*
X1026502Y-31511D03*
Y-11511D03*
Y8489D03*
X1335821Y-31511D03*
Y-11511D03*
Y8489D03*
G54D25*
X32099Y1269464D03*
Y1262464D03*
X48099Y1269464D03*
Y1262464D03*
X61799Y1269464D03*
Y1262464D03*
X77799Y1269464D03*
Y1262464D03*
X91499Y1269464D03*
Y1262464D03*
X86520Y1531262D03*
Y1538262D03*
X107499Y1269464D03*
Y1262464D03*
X121199Y1269464D03*
Y1262464D03*
X137199Y1269464D03*
Y1262464D03*
X133914Y1562234D03*
Y1555234D03*
X150899Y1269464D03*
Y1262464D03*
X149669Y1354514D03*
Y1361514D03*
X166899Y1269464D03*
Y1262464D03*
X177239Y1354514D03*
Y1361514D03*
X168058Y1388498D03*
X176464D03*
X168058Y1395498D03*
X176464D03*
X180599Y1269464D03*
Y1262464D03*
X188215Y1354514D03*
Y1361514D03*
X210299Y1269464D03*
Y1262464D03*
X196599Y1269464D03*
Y1262464D03*
X206201Y1388498D03*
Y1395498D03*
X226448Y1011928D03*
Y1018928D03*
X226299Y1269464D03*
Y1262464D03*
X219980Y1353391D03*
Y1360391D03*
X214607Y1388498D03*
Y1395498D03*
X240072Y983774D03*
Y990774D03*
X239658Y1014086D03*
Y1021086D03*
X239999Y1269464D03*
Y1262464D03*
X256172Y983874D03*
Y990874D03*
X255528Y1014109D03*
X248102Y1014079D03*
X255528Y1021109D03*
X248102Y1021079D03*
X255999Y1269464D03*
Y1262464D03*
X321581Y1308970D03*
Y1301970D03*
X314318Y1308998D03*
Y1301998D03*
X322041Y1346644D03*
Y1353644D03*
X323544Y1368887D03*
Y1361887D03*
X335988Y1289012D03*
Y1296012D03*
X330447Y1346644D03*
Y1353644D03*
X354169Y1323846D03*
X355672Y1339089D03*
X354169Y1330846D03*
X355672Y1346089D03*
X363518Y1289012D03*
Y1296012D03*
X362575Y1323846D03*
Y1330846D03*
X376437Y1275059D03*
X384837D03*
X376437Y1282059D03*
X384837D03*
X387800Y1325663D03*
X386033Y1310043D03*
Y1317043D03*
X387800Y1332663D03*
X397518Y1275059D03*
Y1282059D03*
X394469Y1310043D03*
Y1317043D03*
X409367Y946135D03*
X416247Y946085D03*
X409061Y967360D03*
Y960360D03*
X416061Y967360D03*
Y960360D03*
X409367Y953135D03*
X416247Y953085D03*
X416061Y981840D03*
Y974840D03*
X409061Y981840D03*
Y974840D03*
Y996320D03*
Y989320D03*
X416061Y996320D03*
Y989320D03*
Y1010800D03*
Y1003800D03*
X409061D03*
Y1010800D03*
Y1025284D03*
Y1018284D03*
X416061Y1018280D03*
Y1025280D03*
X419928Y1325663D03*
X418425Y1310043D03*
Y1317043D03*
X419928Y1332663D03*
X423061Y933680D03*
Y946180D03*
Y940680D03*
Y967360D03*
Y960360D03*
Y953180D03*
Y981840D03*
Y974840D03*
Y996320D03*
Y989320D03*
Y1010800D03*
Y1003800D03*
Y1018280D03*
Y1025280D03*
X433274Y1275209D03*
X425274D03*
X433274Y1282209D03*
X425274D03*
X426831Y1310043D03*
Y1317043D03*
X450553Y1310420D03*
Y1317420D03*
X452056Y1325663D03*
Y1332663D03*
X458280Y932398D03*
X465107Y945885D03*
X458280Y945880D03*
Y939398D03*
X465280Y967360D03*
Y960360D03*
X458280Y967360D03*
Y960360D03*
X465107Y952885D03*
X458280Y952880D03*
Y981840D03*
Y974840D03*
X465280Y981840D03*
Y974840D03*
X458280Y996320D03*
Y989320D03*
X465280Y996320D03*
Y989320D03*
Y1010800D03*
Y1003800D03*
X458280Y1010800D03*
Y1003800D03*
X465280Y1018280D03*
Y1025280D03*
X458280Y1018280D03*
Y1025280D03*
X462713Y1275209D03*
Y1282209D03*
X458959Y1310420D03*
Y1317420D03*
X471917Y945805D03*
X472280Y967360D03*
Y960360D03*
X471917Y952805D03*
X472280Y981840D03*
Y974840D03*
Y996320D03*
Y989320D03*
Y1010800D03*
Y1003800D03*
Y1018280D03*
Y1025280D03*
X475821Y1275209D03*
X484221D03*
X475821Y1282209D03*
X484221D03*
X482681Y1310420D03*
Y1317420D03*
X483442Y1325423D03*
Y1332423D03*
X486773Y1440292D03*
Y1447292D03*
X496228Y1289012D03*
Y1296012D03*
X491087Y1310420D03*
Y1317420D03*
X495173Y1440292D03*
Y1447292D03*
X514809Y1323846D03*
X515199Y1339878D03*
X514809Y1330846D03*
X515199Y1346878D03*
X503573Y1440292D03*
Y1447292D03*
X523897Y1289012D03*
Y1296012D03*
X523215Y1323846D03*
Y1330846D03*
X537077Y1316970D03*
Y1309970D03*
X543907Y1316950D03*
Y1309950D03*
X546937Y1346644D03*
Y1353644D03*
X547327Y1369676D03*
Y1362676D03*
X555343Y1346644D03*
Y1353644D03*
X625355Y983045D03*
Y990045D03*
X625340Y1011835D03*
Y1018835D03*
X625299Y1269464D03*
Y1262464D03*
X641560Y981934D03*
Y988934D03*
X641044Y1013821D03*
X648527Y1013299D03*
Y1006299D03*
X633435Y1013821D03*
X641044Y1020821D03*
X633435D03*
X641299Y1269464D03*
Y1262464D03*
X654999Y1269464D03*
Y1262464D03*
X663288Y1354539D03*
Y1361539D03*
X670999Y1269464D03*
Y1262464D03*
X681677Y1388623D03*
Y1395623D03*
X684699Y1269464D03*
Y1262464D03*
X690826Y1354539D03*
Y1361539D03*
X690083Y1389123D03*
Y1396123D03*
X700699Y1269464D03*
Y1262464D03*
X714399Y1269464D03*
Y1262464D03*
X702239Y1354539D03*
Y1361539D03*
X730399Y1269464D03*
Y1262464D03*
X719820Y1388523D03*
X728226D03*
X719820Y1395523D03*
X728226D03*
X744099Y1269464D03*
Y1262464D03*
X733588Y1353416D03*
Y1360416D03*
X760099Y1269464D03*
Y1262464D03*
X773799Y1269464D03*
Y1262464D03*
X789799Y1269464D03*
Y1262464D03*
X803499Y1269464D03*
Y1262464D03*
X819499Y1269464D03*
Y1262464D03*
X833199Y1269464D03*
Y1262464D03*
X840246Y1269464D03*
Y1262464D03*
X968580Y211799D03*
Y204799D03*
X1015841Y1269344D03*
Y1262344D03*
X1024241Y1269444D03*
Y1262444D03*
X1037941Y1269444D03*
Y1262444D03*
X1053941Y1269444D03*
Y1262444D03*
X1067641Y1269444D03*
Y1262444D03*
X1083641Y1269444D03*
Y1262444D03*
X1097341Y1269444D03*
Y1262444D03*
X1113341Y1269444D03*
Y1262444D03*
X1127041Y1269444D03*
Y1262444D03*
X1122980Y1397844D03*
Y1390844D03*
X1143041Y1269444D03*
Y1262444D03*
X1150518Y1397844D03*
Y1390844D03*
X1149775Y1424827D03*
Y1431827D03*
X1141369Y1424827D03*
Y1431827D03*
X1156741Y1269444D03*
Y1262444D03*
X1161931Y1397844D03*
Y1390844D03*
X1186441Y1269444D03*
Y1262444D03*
X1172741Y1269444D03*
Y1262444D03*
X1179512Y1424827D03*
Y1431827D03*
X1202641Y1013744D03*
Y1020744D03*
X1202441Y1269444D03*
Y1262444D03*
X1193280Y1389721D03*
Y1396721D03*
X1187918Y1424827D03*
Y1431827D03*
X1216152Y983844D03*
Y990844D03*
X1215841Y1013744D03*
Y1020744D03*
X1216141Y1269444D03*
Y1262444D03*
X1232241Y983844D03*
Y990844D03*
X1232341Y1013744D03*
X1224241D03*
X1232341Y1020744D03*
X1224241D03*
X1232141Y1269444D03*
Y1262444D03*
X1263333Y267106D03*
Y260106D03*
X1270404Y267032D03*
Y260032D03*
X1289459Y1316998D03*
Y1309998D03*
X1296722Y1316970D03*
Y1309970D03*
X1298182Y1346644D03*
Y1353644D03*
X1299685Y1368887D03*
Y1361887D03*
X1312529Y1289012D03*
Y1296012D03*
X1306588Y1346644D03*
Y1353644D03*
X1330310Y1323846D03*
Y1330846D03*
X1331813Y1339089D03*
Y1346089D03*
X1340059Y1289012D03*
Y1296012D03*
X1338716Y1323846D03*
Y1330846D03*
X1352458Y1275529D03*
X1360858D03*
X1352458Y1282529D03*
X1360858D03*
X1362174Y1310043D03*
Y1317043D03*
X1363941Y1325496D03*
Y1332496D03*
X1379212Y210814D03*
Y217814D03*
X1373739Y1275529D03*
Y1282529D03*
X1370610Y1310043D03*
Y1317043D03*
X1386212Y210814D03*
Y217814D03*
X1392357Y945865D03*
X1385547Y946105D03*
X1392202Y967359D03*
Y960359D03*
X1392357Y952865D03*
X1385202Y967359D03*
Y960359D03*
X1385547Y953105D03*
X1392202Y981839D03*
Y974839D03*
X1385202Y981839D03*
Y974839D03*
X1392202Y996319D03*
Y989319D03*
X1385202Y996319D03*
Y989319D03*
X1392202Y1010799D03*
Y1003799D03*
X1385202D03*
Y1010799D03*
X1392202Y1018279D03*
Y1025279D03*
X1385202Y1025283D03*
Y1018283D03*
X1394566Y1310043D03*
Y1317043D03*
X1396069Y1325496D03*
Y1332496D03*
X1399202Y933379D03*
Y945879D03*
Y940379D03*
Y967359D03*
Y960359D03*
Y952879D03*
Y981839D03*
Y974839D03*
Y996319D03*
Y989319D03*
Y1010799D03*
Y1003799D03*
Y1018279D03*
Y1025279D03*
X1409295Y1275679D03*
X1401235D03*
X1409295Y1282679D03*
X1401235D03*
X1402972Y1310043D03*
Y1317043D03*
X1426694Y1310420D03*
Y1317420D03*
X1428197Y1325496D03*
Y1332496D03*
X1434421Y932397D03*
X1441287Y945975D03*
X1434421Y945879D03*
Y939397D03*
X1441421Y967359D03*
Y960359D03*
X1441287Y952975D03*
X1434421Y967359D03*
Y960359D03*
Y952879D03*
X1441421Y981839D03*
Y974839D03*
X1434421Y981839D03*
Y974839D03*
X1441421Y996319D03*
Y989319D03*
X1434421Y996319D03*
Y989319D03*
X1441421Y1010799D03*
Y1003799D03*
X1434421Y1010799D03*
Y1003799D03*
X1441421Y1018279D03*
Y1025279D03*
X1434421Y1018279D03*
Y1025279D03*
X1438734Y1275679D03*
Y1282679D03*
X1435100Y1310420D03*
Y1317420D03*
X1448127Y945775D03*
X1448421Y967359D03*
Y960359D03*
X1448127Y952775D03*
X1448421Y981839D03*
Y974839D03*
Y996319D03*
Y989319D03*
Y1010799D03*
Y1003799D03*
Y1018279D03*
Y1025279D03*
X1451842Y1275679D03*
X1460242D03*
X1451842Y1282679D03*
X1460242D03*
X1458822Y1310420D03*
Y1317420D03*
X1459583Y1325423D03*
Y1332423D03*
X1472449Y1289012D03*
Y1296012D03*
X1467228Y1310420D03*
Y1317420D03*
X1463294Y1440419D03*
Y1447419D03*
X1471694Y1440419D03*
Y1447419D03*
X1490950Y1323846D03*
Y1330846D03*
X1491340Y1339878D03*
Y1346878D03*
X1480094Y1440419D03*
Y1447419D03*
X1499912Y1290405D03*
Y1297405D03*
X1499247Y1323906D03*
Y1330906D03*
X1513718Y1308970D03*
Y1301970D03*
X1520528Y1309020D03*
Y1302020D03*
X1523078Y1346644D03*
Y1353644D03*
X1523468Y1368876D03*
Y1361876D03*
X1531456Y1346644D03*
Y1353644D03*
X1601397Y983725D03*
Y990725D03*
X1609477Y1013501D03*
X1601482Y1011815D03*
X1609477Y1020501D03*
X1601482Y1018815D03*
X1601441Y1269444D03*
Y1262444D03*
X1617526Y983867D03*
Y990867D03*
X1624206Y1013879D03*
Y1006879D03*
X1617386Y1013066D03*
Y1020066D03*
X1617441Y1269444D03*
Y1262444D03*
X1624454Y1387285D03*
Y1394285D03*
X1631141Y1269444D03*
Y1262444D03*
X1647141Y1269444D03*
Y1262444D03*
X1651992Y1387285D03*
Y1394285D03*
X1651249Y1422119D03*
X1642843D03*
X1651249Y1429119D03*
X1642843D03*
X1660841Y1269444D03*
Y1262444D03*
X1663405Y1387285D03*
Y1394285D03*
X1690541Y1269444D03*
Y1262444D03*
X1676841Y1269444D03*
Y1262444D03*
X1680986Y1422119D03*
X1689392D03*
X1680986Y1429119D03*
X1689392D03*
X1706541Y1269444D03*
Y1262444D03*
X1694954Y1386162D03*
Y1393162D03*
X1720241Y1269444D03*
Y1262444D03*
X1736241Y1269444D03*
Y1262444D03*
X1749941Y1269444D03*
Y1262444D03*
X1770898Y233128D03*
Y226128D03*
X1762878Y233128D03*
Y226128D03*
X1765941Y1269444D03*
Y1262444D03*
X1779378Y233128D03*
Y226128D03*
X1784810Y276992D03*
Y283992D03*
X1779641Y1269444D03*
Y1262444D03*
X1791850Y277002D03*
Y284002D03*
X1790320Y298032D03*
Y305032D03*
X1795641Y1269444D03*
Y1262444D03*
X1809341Y1269444D03*
Y1262444D03*
X1816714Y1269444D03*
Y1262444D03*
G54D34*
X150927Y1237271D03*
Y1246719D03*
X268597Y1255061D03*
Y1264509D03*
X833207Y1239961D03*
Y1249409D03*
X1127069Y1237271D03*
Y1246719D03*
X1216149Y1239961D03*
Y1249409D03*
X1780500Y314299D03*
Y323747D03*
X1809349Y1236461D03*
Y1245909D03*
G54D52*
X396332Y828421D03*
X402132D03*
X396332Y834842D03*
X402132D03*
X423955Y1646993D03*
X429755D03*
X423965Y1642006D03*
X429765D03*
X451395Y1636501D03*
X445595D03*
X661820Y399862D03*
X666870Y197272D03*
X672670D03*
X667620Y399862D03*
X678395D03*
X684195D03*
X698320D03*
X704120D03*
X710120Y493362D03*
X704320D03*
X716320Y399862D03*
X722120D03*
X742620D03*
X736820D03*
X919269Y475794D03*
X925069D03*
X932094Y477311D03*
X937894D03*
X990600Y396117D03*
X996400D03*
X1027241Y397305D03*
X1033041D03*
X1026139Y412728D03*
X1031939D03*
X1168462Y190588D03*
X1168140Y197742D03*
Y205842D03*
X1174262Y190588D03*
X1173940Y197742D03*
Y205842D03*
X1187460Y185582D03*
X1193260D03*
X1186938Y214133D03*
X1192738D03*
X1186938Y208733D03*
X1192738D03*
X1250101Y256098D03*
X1255901D03*
X1279289Y294768D03*
Y289368D03*
X1285189Y294768D03*
Y289368D03*
X1372473Y834841D03*
X1378273D03*
X1372473Y828420D03*
X1378273D03*
X1371226Y1406454D03*
X1377026D03*
X1392750Y230152D03*
X1386950D03*
G54D16*
X44396Y444564D03*
Y442989D03*
Y441415D03*
Y439840D03*
X50696D03*
Y441415D03*
Y442989D03*
Y444564D03*
X550700Y114289D03*
Y112714D03*
Y111140D03*
Y109565D03*
X557000D03*
Y111140D03*
Y112714D03*
Y114289D03*
G54D43*
X238780Y1648385D03*
X230906Y1644448D03*
X238780Y1662558D03*
X230906Y1658621D03*
X238780Y1676732D03*
X230906Y1672795D03*
X238780Y1690905D03*
X230906Y1686968D03*
X238780Y1705078D03*
X230906Y1701141D03*
Y1715314D03*
X238780Y1719251D03*
X230906Y1729488D03*
X238780Y1733425D03*
X254528Y1648385D03*
X246654Y1644448D03*
X254528Y1662558D03*
X246654Y1658621D03*
X254528Y1676732D03*
X246654Y1672795D03*
X254528Y1690905D03*
X246654Y1686968D03*
X254528Y1705078D03*
X246654Y1701141D03*
Y1715314D03*
X254528Y1719251D03*
X246654Y1729488D03*
X254528Y1733425D03*
X270276Y1648385D03*
X262402Y1644448D03*
X270276Y1662558D03*
X262402Y1658621D03*
X270276Y1676732D03*
X262402Y1672795D03*
X270276Y1690905D03*
X262402Y1686968D03*
X270276Y1705078D03*
X262402Y1701141D03*
Y1715314D03*
X270276Y1719251D03*
X262402Y1729488D03*
X270276Y1733425D03*
X286024Y1648385D03*
X278150Y1644448D03*
X286024Y1662558D03*
X278150Y1658621D03*
X286024Y1676732D03*
X278150Y1672795D03*
X286024Y1690905D03*
X278150Y1686968D03*
X286024Y1705078D03*
X278150Y1701141D03*
Y1715314D03*
X286024Y1719251D03*
X278150Y1729488D03*
X286024Y1733425D03*
X297835Y1672795D03*
X305709Y1676732D03*
X297835Y1686968D03*
X305709Y1690905D03*
X297835Y1701141D03*
X305709Y1705078D03*
X297835Y1715314D03*
X305709Y1719251D03*
X297835Y1729488D03*
X305709Y1733425D03*
X313583Y1672795D03*
X321457Y1676732D03*
X313583Y1686968D03*
X321457Y1690905D03*
X313583Y1701141D03*
X321457Y1705078D03*
X313583Y1715314D03*
X321457Y1719251D03*
X313583Y1729488D03*
X321457Y1733425D03*
X329331Y1672795D03*
X337205Y1676732D03*
X329331Y1686968D03*
X337205Y1690905D03*
X329331Y1701141D03*
X337205Y1705078D03*
X329331Y1715314D03*
X337205Y1719251D03*
X329331Y1729488D03*
X337205Y1733425D03*
X345079Y1672795D03*
X352953Y1676732D03*
X345079Y1686968D03*
X352953Y1690905D03*
X345079Y1701141D03*
X352953Y1705078D03*
X345079Y1715314D03*
X352953Y1719251D03*
X345079Y1729488D03*
X352953Y1733425D03*
X495079Y1672795D03*
Y1686968D03*
Y1701141D03*
Y1715314D03*
Y1729488D03*
X510827Y1672795D03*
X502953Y1676732D03*
X518701D03*
X510827Y1686968D03*
X502953Y1690905D03*
X518701D03*
X510827Y1701141D03*
X502953Y1705078D03*
X518701D03*
X510827Y1715314D03*
X502953Y1719251D03*
X518701D03*
X510827Y1729488D03*
X502953Y1733425D03*
X518701D03*
X526575Y1672795D03*
X534449Y1676732D03*
X526575Y1686968D03*
X534449Y1690905D03*
X526575Y1701141D03*
X534449Y1705078D03*
X526575Y1715314D03*
X534449Y1719251D03*
X526575Y1729488D03*
X534449Y1733425D03*
X542323Y1672795D03*
X550197Y1676732D03*
X542323Y1686968D03*
X550197Y1690905D03*
X542323Y1701141D03*
X550197Y1705078D03*
X542323Y1715314D03*
X550197Y1719251D03*
X542323Y1729488D03*
X550197Y1733425D03*
X562008Y1672795D03*
Y1686968D03*
Y1701141D03*
Y1715314D03*
Y1729488D03*
X577756Y1672795D03*
X569882Y1676732D03*
X577756Y1686968D03*
X569882Y1690905D03*
X577756Y1701141D03*
X569882Y1705078D03*
X577756Y1715314D03*
X569882Y1719251D03*
X577756Y1729488D03*
X569882Y1733425D03*
X593504Y1672795D03*
X585630Y1676732D03*
X593504Y1686968D03*
X585630Y1690905D03*
X593504Y1701141D03*
X585630Y1705078D03*
X593504Y1715314D03*
X585630Y1719251D03*
X593504Y1729488D03*
X585630Y1733425D03*
X609252Y1672795D03*
X601378Y1676732D03*
X609252Y1686968D03*
X601378Y1690905D03*
X609252Y1701141D03*
X601378Y1705078D03*
X609252Y1715314D03*
X601378Y1719251D03*
X609252Y1729488D03*
X601378Y1733425D03*
X617126Y1676732D03*
Y1690905D03*
Y1705078D03*
Y1719251D03*
Y1733425D03*
X1238780Y1672795D03*
X1246654Y1676732D03*
X1238780Y1686968D03*
X1246654Y1690905D03*
X1238780Y1701141D03*
X1246654Y1705078D03*
X1238780Y1715314D03*
X1246654Y1719251D03*
X1238780Y1729488D03*
X1246654Y1733425D03*
X1254528Y1672795D03*
X1262402Y1676732D03*
X1254528Y1686968D03*
X1262402Y1690905D03*
X1254528Y1701141D03*
X1262402Y1705078D03*
X1254528Y1715314D03*
X1262402Y1719251D03*
X1254528Y1729488D03*
X1262402Y1733425D03*
X1270276Y1672795D03*
X1278150Y1676732D03*
X1270276Y1686968D03*
X1278150Y1690905D03*
X1270276Y1701141D03*
X1278150Y1705078D03*
X1270276Y1715314D03*
X1278150Y1719251D03*
X1270276Y1729488D03*
X1278150Y1733425D03*
X1286024Y1672795D03*
X1293898Y1676732D03*
X1286024Y1686968D03*
X1293898Y1690905D03*
X1286024Y1701141D03*
X1293898Y1705078D03*
X1286024Y1715314D03*
X1293898Y1719251D03*
X1286024Y1729488D03*
X1293898Y1733425D03*
X1305709Y1672795D03*
X1313583Y1676732D03*
X1305709Y1686968D03*
X1313583Y1690905D03*
X1305709Y1701141D03*
X1313583Y1705078D03*
X1305709Y1715314D03*
X1313583Y1719251D03*
X1305709Y1729488D03*
X1313583Y1733425D03*
X1321457Y1672795D03*
X1329331Y1676732D03*
X1321457Y1686968D03*
X1329331Y1690905D03*
X1321457Y1701141D03*
X1329331Y1705078D03*
X1321457Y1715314D03*
X1329331Y1719251D03*
X1321457Y1729488D03*
X1329331Y1733425D03*
X1337205Y1672795D03*
X1345079Y1676732D03*
X1337205Y1686968D03*
X1345079Y1690905D03*
X1337205Y1701141D03*
X1345079Y1705078D03*
X1337205Y1715314D03*
X1345079Y1719251D03*
X1337205Y1729488D03*
X1345079Y1733425D03*
X1352953Y1672795D03*
X1360827Y1676732D03*
X1352953Y1686968D03*
X1360827Y1690905D03*
X1352953Y1701141D03*
X1360827Y1705078D03*
X1352953Y1715314D03*
X1360827Y1719251D03*
X1352953Y1729488D03*
X1360827Y1733425D03*
X1502953Y1672795D03*
X1510827Y1676732D03*
X1502953Y1686968D03*
X1510827Y1690905D03*
X1502953Y1701141D03*
X1510827Y1705078D03*
X1502953Y1715314D03*
X1510827Y1719251D03*
X1502953Y1729488D03*
X1510827Y1733425D03*
X1518701Y1672795D03*
X1526575Y1676732D03*
X1518701Y1686968D03*
X1526575Y1690905D03*
X1518701Y1701141D03*
X1526575Y1705078D03*
X1518701Y1715314D03*
X1526575Y1719251D03*
X1518701Y1729488D03*
X1526575Y1733425D03*
X1534449Y1672795D03*
X1542323Y1676732D03*
X1534449Y1686968D03*
X1542323Y1690905D03*
X1534449Y1701141D03*
X1542323Y1705078D03*
X1534449Y1715314D03*
X1542323Y1719251D03*
X1534449Y1729488D03*
X1542323Y1733425D03*
X1550197Y1672795D03*
X1558071Y1676732D03*
X1550197Y1686968D03*
X1558071Y1690905D03*
X1550197Y1701141D03*
X1558071Y1705078D03*
X1550197Y1715314D03*
X1558071Y1719251D03*
X1550197Y1729488D03*
X1558071Y1733425D03*
X1569882Y1672795D03*
Y1686968D03*
Y1701141D03*
Y1715314D03*
Y1729488D03*
X1585630Y1672795D03*
X1577756Y1676732D03*
X1585630Y1686968D03*
X1577756Y1690905D03*
X1585630Y1701141D03*
X1577756Y1705078D03*
X1585630Y1715314D03*
X1577756Y1719251D03*
X1585630Y1729488D03*
X1577756Y1733425D03*
X1601378Y1672795D03*
X1593504Y1676732D03*
X1601378Y1686968D03*
X1593504Y1690905D03*
X1601378Y1701141D03*
X1593504Y1705078D03*
X1601378Y1715314D03*
X1593504Y1719251D03*
X1601378Y1729488D03*
X1593504Y1733425D03*
X1617126Y1672795D03*
X1609252Y1676732D03*
X1625000D03*
X1617126Y1686968D03*
X1609252Y1690905D03*
X1625000D03*
X1617126Y1701141D03*
X1609252Y1705078D03*
X1625000D03*
X1617126Y1715314D03*
X1609252Y1719251D03*
X1625000D03*
X1617126Y1729488D03*
X1609252Y1733425D03*
X1625000D03*
G54D61*
X500554Y98629D03*
Y108275D03*
X501932Y98629D03*
X503310D03*
X504688D03*
X506066D03*
Y108275D03*
X504688D03*
X503310D03*
X501932D03*
G54D53*
X387842Y1593517D03*
Y1591417D03*
X391417Y1593517D03*
Y1591417D03*
X663561Y38286D03*
Y36186D03*
X666889Y38287D03*
Y36187D03*
X1327633Y252162D03*
Y254262D03*
X1343782Y243266D03*
Y245366D03*
X1340182Y243266D03*
Y245366D03*
X1339990Y260466D03*
Y262566D03*
X1336390Y260466D03*
Y262566D03*
X1331233Y252162D03*
Y254262D03*
X1347448Y251266D03*
Y253366D03*
X1353702Y243266D03*
Y245366D03*
X1357302Y243266D03*
Y245366D03*
X1360450Y251266D03*
Y253366D03*
X1351048Y251266D03*
Y253366D03*
X1364050Y251266D03*
Y253366D03*
G54D71*
X720360Y-20516D03*
Y-22484D03*
X837320Y9484D03*
Y7516D03*
X983580Y-22484D03*
Y-20516D03*
Y7516D03*
Y9484D03*
X1029752Y-30527D03*
Y-32495D03*
Y-10527D03*
Y-12495D03*
Y9473D03*
Y7505D03*
X1292972Y-32495D03*
Y-30527D03*
Y-12495D03*
Y-10527D03*
Y7505D03*
Y9473D03*
X1339071Y-30527D03*
Y-32495D03*
Y-10527D03*
Y-12495D03*
Y9473D03*
Y7505D03*
X1485331Y-32495D03*
Y-30527D03*
Y-12495D03*
Y-10527D03*
Y7505D03*
Y9473D03*
G54D62*
X503310Y103452D03*
G54D17*
X30771Y441130D03*
Y445519D03*
X40084Y722374D03*
Y726874D03*
X37861Y1254400D03*
X62327Y393079D03*
X62329Y388462D03*
X48384Y722374D03*
Y726874D03*
X68300Y754726D03*
Y759246D03*
X67793Y1254593D03*
X104966Y493474D03*
Y513374D03*
X97228Y1254464D03*
X117516Y642762D03*
X114963Y657550D03*
X114999Y646327D03*
X114963Y651734D03*
X126694Y1254528D03*
X135707Y652919D03*
Y656431D03*
X132389Y1242353D03*
X144063Y493640D03*
Y501640D03*
Y497640D03*
Y505550D03*
X144013Y518810D03*
Y514980D03*
X154505Y1253412D03*
X147915Y1252964D03*
X148506Y1407778D03*
X192036Y681062D03*
X186270Y1255943D03*
X203056Y565982D03*
X204652Y600801D03*
X204562Y634882D03*
X208935Y1244936D03*
X210770Y572619D03*
Y606619D03*
Y640619D03*
X216154Y1255944D03*
X241393Y704825D03*
X226396Y1242283D03*
X258997Y64455D03*
X258949Y60345D03*
X258952Y56160D03*
X302227Y177279D03*
Y181279D03*
X320361Y205049D03*
X351513Y705965D03*
X393425Y1404085D03*
Y1407605D03*
X417563Y929166D03*
X435000Y1415275D03*
X434990Y1407789D03*
X437516Y380862D03*
X437970Y1420659D03*
X448790Y1407229D03*
X437455Y1411504D03*
X446486Y1424269D03*
X447876Y1626352D03*
X453896Y1401282D03*
X477973Y1398402D03*
X479452Y1394447D03*
X536341Y112592D03*
X593238Y740955D03*
X586228Y740985D03*
X614973Y400149D03*
Y404179D03*
X611874Y939877D03*
X616736Y38702D03*
X625599Y146942D03*
X625597Y151559D03*
X631736Y431062D03*
Y457862D03*
Y477862D03*
Y472862D03*
Y467862D03*
Y462862D03*
X616736Y467862D03*
X631736Y487862D03*
Y482862D03*
X623308Y1257336D03*
Y1253293D03*
X646736Y421362D03*
Y438862D03*
Y472862D03*
Y477862D03*
Y467862D03*
Y482862D03*
X663236Y408362D03*
Y404362D03*
X656304Y1252895D03*
X677044Y35067D03*
X679811Y408362D03*
Y404362D03*
X688568Y779977D03*
X691316Y1257062D03*
X699736Y408362D03*
Y404362D03*
X701736Y1301162D03*
Y1297162D03*
X704658Y1563733D03*
X704628Y1587683D03*
Y1591683D03*
X706228Y1601983D03*
X708612Y1663842D03*
X708625Y1667841D03*
X717736Y408362D03*
Y404362D03*
X719035Y1253356D03*
X719668Y1569493D03*
X726768D03*
X740506Y412692D03*
X754393Y273399D03*
X757555Y286632D03*
X759856Y474862D03*
X750676Y1256762D03*
X775736Y423212D03*
Y418212D03*
X774856Y474862D03*
X762923Y761555D03*
X793640Y763996D03*
X786043Y759655D03*
X793643Y758455D03*
X786043Y763855D03*
X778384Y1253277D03*
X798015Y295488D03*
X801185Y312773D03*
X797915Y303188D03*
X802193Y763915D03*
Y759665D03*
X807849Y1253512D03*
X824383Y760215D03*
X824480Y764316D03*
X842736Y220362D03*
X840413Y770025D03*
X839386Y1252392D03*
X849636Y216362D03*
X849736Y209362D03*
X930111Y189386D03*
X930311Y193386D03*
X928441Y201612D03*
X934905Y493701D03*
X930681Y512098D03*
X933186Y521348D03*
X931156Y980462D03*
X931294Y986143D03*
X970366Y380952D03*
X966372Y390302D03*
Y394178D03*
X987275Y341799D03*
X987395Y421961D03*
X999575Y341829D03*
X1001762Y419162D03*
X1018016Y380862D03*
Y385862D03*
Y394362D03*
Y398362D03*
X1015779Y416974D03*
X1013921Y1254263D03*
X1043423Y1254713D03*
X1073120Y1254504D03*
X1116923Y1257449D03*
X1133064Y1259862D03*
X1146493Y606082D03*
X1146503Y599122D03*
X1171516Y1016362D03*
X1192017Y1256140D03*
X1208609Y120962D03*
X1216051Y121002D03*
X1201624Y588714D03*
X1217024Y1256789D03*
X1228609Y129962D03*
Y140962D03*
Y144962D03*
X1229139Y152612D03*
X1226236Y205862D03*
Y217862D03*
Y209862D03*
Y213862D03*
X1239109Y201462D03*
Y205462D03*
Y209462D03*
Y213462D03*
X1239793Y907485D03*
X1256923Y741785D03*
X1270174Y235206D03*
X1282789Y190387D03*
X1284909Y276407D03*
X1302036Y99262D03*
X1312638Y177016D03*
X1321966Y167472D03*
X1322036Y171277D03*
X1315951Y198088D03*
X1315826Y193002D03*
X1315951Y202141D03*
X1323299Y741707D03*
X1342107Y124718D03*
X1349108Y120618D03*
X1356078Y124123D03*
X1377094Y1330133D03*
X1390453Y223754D03*
X1387021Y235188D03*
X1393975Y928806D03*
X1409257Y1330159D03*
X1411141Y1415275D03*
X1411131Y1407789D03*
X1428816Y1401948D03*
X1425931Y1408229D03*
X1413596Y1411504D03*
X1414111Y1420659D03*
X1422497Y1424249D03*
X1437213Y712575D03*
X1441234Y1330312D03*
X1438776Y1570772D03*
X1453236Y145362D03*
X1446463Y746305D03*
X1464736Y169862D03*
X1502492Y741315D03*
X1499358Y745240D03*
X1514816Y312712D03*
X1589094Y211526D03*
X1589078Y231490D03*
X1609530Y1254944D03*
X1636630Y1254844D03*
X1654809Y522176D03*
X1654745Y540071D03*
X1661966Y607332D03*
X1666430Y1255044D03*
X1686193Y466950D03*
X1681454Y488288D03*
X1685185Y502279D03*
X1693792Y521507D03*
Y525507D03*
Y541507D03*
Y529507D03*
Y533507D03*
Y545507D03*
X1696030Y1254244D03*
X1718877Y475752D03*
Y472252D03*
Y479252D03*
X1732310Y61639D03*
X1732358Y65749D03*
X1725630Y1254344D03*
X1755130D03*
X1771891Y173903D03*
Y178303D03*
X1785330Y1254744D03*
X1792486Y1505652D03*
X1803336Y1256426D03*
G54D44*
X238780Y1643661D03*
X230906Y1649173D03*
X238780Y1653110D03*
Y1657834D03*
X230906Y1653897D03*
Y1663346D03*
X238780Y1667283D03*
Y1672007D03*
X230906Y1668070D03*
X254528Y1643661D03*
X246654Y1649173D03*
X254528Y1653110D03*
Y1657834D03*
X246654Y1653897D03*
Y1663346D03*
X254528Y1667283D03*
Y1672007D03*
X246654Y1668070D03*
Y1734212D03*
X270276Y1643661D03*
X262402Y1649173D03*
Y1653897D03*
Y1663346D03*
X270276Y1667283D03*
Y1672007D03*
X262402Y1668070D03*
Y1734212D03*
X286024Y1643661D03*
X278150Y1649173D03*
Y1653897D03*
Y1663346D03*
Y1668070D03*
Y1734212D03*
X305709Y1672007D03*
X321457D03*
X313583Y1734212D03*
X337205Y1672007D03*
X329331Y1734212D03*
X352953Y1672007D03*
X345079Y1734212D03*
X502953Y1672007D03*
X510827Y1734212D03*
X518701Y1672007D03*
X534449D03*
X526575Y1734212D03*
X550197Y1672007D03*
X542323Y1734212D03*
X569882Y1672007D03*
X577756Y1734212D03*
X585630Y1672007D03*
X593504Y1734212D03*
X601378Y1672007D03*
X609252Y1734212D03*
X617126Y1672007D03*
X1246654D03*
X1262402D03*
X1254528Y1734212D03*
X1278150Y1672007D03*
X1270276Y1734212D03*
X1293898Y1672007D03*
X1286024Y1734212D03*
X1313583Y1672007D03*
X1329331D03*
X1321457Y1734212D03*
X1345079Y1672007D03*
X1337205Y1734212D03*
X1360827Y1672007D03*
X1352953Y1734212D03*
X1510827Y1672007D03*
X1526575D03*
X1518701Y1734212D03*
X1542323Y1672007D03*
X1534449Y1734212D03*
X1558071Y1672007D03*
X1550197Y1734212D03*
X1577756Y1672007D03*
X1585630Y1734212D03*
X1593504Y1672007D03*
X1601378Y1734212D03*
X1609252Y1672007D03*
X1617126Y1734212D03*
X1625000Y1672007D03*
G54D26*
X57646Y12480D03*
X137272D03*
X186622D03*
X266858D03*
X315598D03*
X502528Y33268D03*
X582154D03*
X631504D03*
X711740D03*
X760480D03*
X1532055Y12480D03*
X1611681D03*
X1661031D03*
X1741267D03*
X1790007D03*
G54D35*
X159474Y1320753D03*
X183847Y1320778D03*
X208247D03*
X275289Y575702D03*
Y599861D03*
Y624015D03*
Y648169D03*
X278126Y676260D03*
Y700414D03*
X395771Y1242785D03*
X420171D03*
X444493D03*
X468893D03*
X493293D03*
X676508Y224606D03*
X673093Y1320778D03*
X697466Y1320803D03*
X721866D03*
X1100800Y251488D03*
X1100700Y275788D03*
X1131100Y1357088D03*
X1155500D03*
X1179900D03*
X1371912Y1242785D03*
X1396312D03*
X1420634D03*
X1445034D03*
X1469434D03*
X1577000Y591888D03*
Y616388D03*
Y640888D03*
Y665288D03*
Y689788D03*
Y714288D03*
X1634259Y1354374D03*
X1658632Y1354399D03*
X1683032D03*
G54D80*
X841240Y1407480D03*
X832154Y1411244D03*
X828390Y1420330D03*
X832154Y1429416D03*
X841240Y1433180D03*
X850326Y1411244D03*
X854090Y1420330D03*
X850326Y1429416D03*
X1003390Y1420330D03*
X1016240Y1407480D03*
X1007154Y1411244D03*
Y1429416D03*
X1016240Y1433180D03*
X1025326Y1411244D03*
X1029090Y1420330D03*
X1025326Y1429416D03*
G54D81*
X841240Y1420330D03*
X1016240D03*
G54D72*
X725073Y1241963D03*
X734521D03*
X1700586Y1235879D03*
X1710034D03*
G54D54*
X412561Y933298D03*
X417261D03*
X407861D03*
X412561Y939098D03*
X417261D03*
X407861D03*
X429628Y1631147D03*
Y1636947D03*
X438255Y1614977D03*
Y1609177D03*
X464080Y932964D03*
X468780D03*
X464080Y938764D03*
X468780D03*
X473480Y932964D03*
Y938764D03*
X474246Y1412784D03*
Y1418684D03*
X479646Y1412784D03*
Y1418684D03*
X686220Y490762D03*
Y484962D03*
X906493Y476404D03*
X900460Y490022D03*
X906493Y482204D03*
X900460Y495822D03*
X913401Y475904D03*
X924782Y487212D03*
Y481412D03*
X919515D03*
Y487212D03*
X913401Y481704D03*
X956708Y381166D03*
X951914Y381162D03*
X956708Y386966D03*
X951914Y386962D03*
X1031900Y418517D03*
Y424317D03*
X1282145Y260251D03*
Y266051D03*
X1276901Y260225D03*
Y266025D03*
X1313264Y227309D03*
Y233109D03*
X1307864Y227309D03*
Y233109D03*
X1323896Y227362D03*
Y233162D03*
X1318627Y227279D03*
Y233079D03*
X1362309Y217419D03*
Y211619D03*
X1373111Y217452D03*
Y211652D03*
X1367711Y217404D03*
Y211604D03*
X1388702Y932963D03*
X1393402D03*
X1384002D03*
X1388702Y938763D03*
X1393402D03*
X1384002D03*
X1440221Y932963D03*
X1444921D03*
X1440221Y938763D03*
X1444921D03*
X1449621Y932963D03*
Y938763D03*
X1450387Y1412744D03*
Y1418644D03*
X1455787Y1412744D03*
Y1418644D03*
G54D63*
X517115Y107550D03*
Y111060D03*
X520265Y107550D03*
Y111060D03*
X931426Y527751D03*
X934576D03*
X931426D03*
X928276D03*
X931503Y533077D03*
X934653D03*
X931503D03*
X928353D03*
X1011630Y218253D03*
X1014780D03*
X1011630D03*
X1008480D03*
X1330873Y542647D03*
D03*
X1327723D03*
X1330796Y537321D03*
D03*
X1327646D03*
X1334023Y542647D03*
X1333946Y537321D03*
G54D18*
X33738Y441130D03*
Y445519D03*
X43051Y722374D03*
Y726874D03*
X40828Y1254400D03*
X51351Y722374D03*
Y726874D03*
X65294Y393079D03*
X65296Y388462D03*
X71267Y754726D03*
Y759246D03*
X70760Y1254593D03*
X107933Y493474D03*
Y513374D03*
X100195Y1254464D03*
X120483Y642762D03*
X117930Y657550D03*
X117966Y646327D03*
X117930Y651734D03*
X138674Y652919D03*
Y656431D03*
X135356Y1242353D03*
X129661Y1254528D03*
X147030Y493640D03*
Y501640D03*
Y497640D03*
Y505550D03*
X146980Y518810D03*
Y514980D03*
X157472Y1253412D03*
X150882Y1252964D03*
X151473Y1407778D03*
X189237Y1255943D03*
X206023Y565982D03*
X207619Y600801D03*
X207529Y634882D03*
X195003Y681062D03*
X213737Y572619D03*
Y606619D03*
Y640619D03*
X219121Y1255944D03*
X211902Y1244936D03*
X229363Y1242283D03*
X244360Y704825D03*
X261964Y64455D03*
X261916Y60345D03*
X261919Y56160D03*
X305194Y177279D03*
Y181279D03*
X323328Y205049D03*
X354480Y705965D03*
X396392Y1404085D03*
Y1407605D03*
X420530Y929166D03*
X440483Y380862D03*
X440937Y1420659D03*
X451757Y1407229D03*
X440422Y1411504D03*
X437967Y1415275D03*
X437957Y1407789D03*
X449453Y1424269D03*
X450843Y1626352D03*
X456863Y1401282D03*
X480940Y1398402D03*
X482419Y1394447D03*
X539308Y112592D03*
X596205Y740955D03*
X589195Y740985D03*
X614841Y939877D03*
X619703Y38702D03*
X628566Y146942D03*
X628564Y151559D03*
X617940Y400149D03*
Y404179D03*
X619703Y467862D03*
X626275Y1257336D03*
Y1253293D03*
X634703Y431062D03*
Y457862D03*
Y477862D03*
Y472862D03*
Y467862D03*
Y462862D03*
Y487862D03*
Y482862D03*
X649703Y421362D03*
Y438862D03*
Y472862D03*
Y477862D03*
Y467862D03*
Y482862D03*
X659271Y1252895D03*
X680011Y35067D03*
X666203Y408362D03*
Y404362D03*
X682778Y408362D03*
Y404362D03*
X691535Y779977D03*
X694283Y1257062D03*
X702703Y408362D03*
Y404362D03*
X704703Y1301162D03*
Y1297162D03*
X707625Y1563733D03*
X707595Y1587683D03*
Y1591683D03*
X709195Y1601983D03*
X711579Y1663842D03*
X711592Y1667841D03*
X720703Y408362D03*
Y404362D03*
X722002Y1253356D03*
X722635Y1569493D03*
X743473Y412692D03*
X729735Y1569493D03*
X757360Y273399D03*
X760522Y286632D03*
X753643Y1256762D03*
X762823Y474862D03*
X777823D03*
X765890Y761555D03*
X778703Y423212D03*
Y418212D03*
X789010Y759655D03*
Y763855D03*
X781351Y1253277D03*
X800982Y295488D03*
X804152Y312773D03*
X800882Y303188D03*
X805160Y763915D03*
Y759665D03*
X796607Y763996D03*
X796610Y758455D03*
X810816Y1253512D03*
X827350Y760215D03*
X827447Y764316D03*
X843380Y770025D03*
X842353Y1252392D03*
X852603Y216362D03*
X852703Y209362D03*
X845703Y220362D03*
X933078Y189386D03*
X933278Y193386D03*
X931408Y201612D03*
X937872Y493701D03*
X933648Y512098D03*
X936153Y521348D03*
X934123Y980462D03*
X934261Y986143D03*
X973333Y380952D03*
X969339Y390302D03*
Y394178D03*
X1002542Y341829D03*
X990242Y341799D03*
X990362Y421961D03*
X1004729Y419162D03*
X1020983Y380862D03*
Y385862D03*
Y394362D03*
Y398362D03*
X1018746Y416974D03*
X1016888Y1254263D03*
X1046390Y1254713D03*
X1076087Y1254504D03*
X1119890Y1257449D03*
X1136031Y1259862D03*
X1149460Y606082D03*
X1149470Y599122D03*
X1174483Y1016362D03*
X1194984Y1256140D03*
X1211576Y120962D03*
X1204591Y588714D03*
X1231576Y129962D03*
X1219018Y121002D03*
X1231576Y140962D03*
Y144962D03*
X1232106Y152612D03*
X1229203Y205862D03*
Y217862D03*
Y209862D03*
Y213862D03*
X1219991Y1256789D03*
X1242076Y201462D03*
Y205462D03*
Y209462D03*
Y213462D03*
X1242760Y907485D03*
X1259890Y741785D03*
X1273141Y235206D03*
X1285756Y190387D03*
X1287876Y276407D03*
X1305003Y99262D03*
X1324933Y167472D03*
X1315605Y177016D03*
X1325003Y171277D03*
X1318918Y198088D03*
X1318793Y193002D03*
X1318918Y202141D03*
X1326266Y741707D03*
X1345074Y124718D03*
X1352075Y120618D03*
X1359045Y124123D03*
X1380061Y1330133D03*
X1393420Y223754D03*
X1389988Y235188D03*
X1396942Y928806D03*
X1412224Y1330159D03*
X1414108Y1415275D03*
X1414098Y1407789D03*
X1428898Y1408229D03*
X1416563Y1411504D03*
X1417078Y1420659D03*
X1425464Y1424249D03*
X1440180Y712575D03*
X1444201Y1330312D03*
X1431783Y1401948D03*
X1441743Y1570772D03*
X1456203Y145362D03*
X1449430Y746305D03*
X1467703Y169862D03*
X1505459Y741315D03*
X1502325Y745240D03*
X1517783Y312712D03*
X1592061Y211526D03*
X1592045Y231490D03*
X1612497Y1254944D03*
X1639597Y1254844D03*
X1657776Y522176D03*
X1657712Y540071D03*
X1664933Y607332D03*
X1669397Y1255044D03*
X1689160Y466950D03*
X1684421Y488288D03*
X1688152Y502279D03*
X1696759Y521507D03*
Y525507D03*
Y541507D03*
Y529507D03*
Y533507D03*
Y545507D03*
X1698997Y1254244D03*
X1721844Y475752D03*
Y472252D03*
Y479252D03*
X1735277Y61639D03*
X1735325Y65749D03*
X1728597Y1254344D03*
X1758097D03*
X1774858Y173903D03*
Y178303D03*
X1788297Y1254744D03*
X1795453Y1505652D03*
X1806303Y1256426D03*
G54D45*
X238780Y1681456D03*
X230906Y1677519D03*
Y1682244D03*
X238780Y1686180D03*
Y1695629D03*
X230906Y1691692D03*
Y1696417D03*
X238780Y1700354D03*
Y1709803D03*
Y1714527D03*
X230906Y1705866D03*
Y1710590D03*
X238780Y1723976D03*
Y1728700D03*
X230906Y1720039D03*
Y1724763D03*
X254528Y1681456D03*
X246654Y1677519D03*
Y1682244D03*
X254528Y1686180D03*
Y1695629D03*
X246654Y1691692D03*
Y1696417D03*
X254528Y1700354D03*
Y1709803D03*
Y1714527D03*
X246654Y1705866D03*
Y1710590D03*
X254528Y1723976D03*
Y1728700D03*
X246654Y1720039D03*
Y1724763D03*
X270276Y1653110D03*
Y1657834D03*
Y1681456D03*
X262402Y1677519D03*
Y1682244D03*
X270276Y1686180D03*
Y1695629D03*
X262402Y1691692D03*
Y1696417D03*
X270276Y1700354D03*
Y1709803D03*
Y1714527D03*
X262402Y1705866D03*
Y1710590D03*
X270276Y1723976D03*
Y1728700D03*
X262402Y1720039D03*
Y1724763D03*
X286024Y1653110D03*
Y1657834D03*
Y1667283D03*
Y1672007D03*
Y1681456D03*
X278150Y1677519D03*
Y1682244D03*
X286024Y1686180D03*
Y1695629D03*
X278150Y1691692D03*
Y1696417D03*
X286024Y1700354D03*
Y1709803D03*
Y1714527D03*
X278150Y1705866D03*
Y1710590D03*
X286024Y1723976D03*
Y1728700D03*
X278150Y1720039D03*
Y1724763D03*
X297835Y1677519D03*
Y1682244D03*
X305709Y1681456D03*
Y1686180D03*
X297835Y1691692D03*
Y1696417D03*
X305709Y1695629D03*
Y1700354D03*
X297835Y1705866D03*
Y1710590D03*
X305709Y1709803D03*
Y1714527D03*
X297835Y1720039D03*
Y1724763D03*
X305709Y1723976D03*
Y1728700D03*
X313583Y1677519D03*
Y1682244D03*
X321457Y1681456D03*
Y1686180D03*
X313583Y1691692D03*
Y1696417D03*
X321457Y1695629D03*
Y1700354D03*
X313583Y1705866D03*
Y1710590D03*
X321457Y1709803D03*
Y1714527D03*
X313583Y1720039D03*
Y1724763D03*
X321457Y1723976D03*
Y1728700D03*
X329331Y1677519D03*
Y1682244D03*
X337205Y1681456D03*
Y1686180D03*
X329331Y1691692D03*
Y1696417D03*
X337205Y1695629D03*
Y1700354D03*
X329331Y1705866D03*
Y1710590D03*
X337205Y1709803D03*
Y1714527D03*
X329331Y1720039D03*
Y1724763D03*
X337205Y1723976D03*
Y1728700D03*
X345079Y1677519D03*
Y1682244D03*
X352953Y1681456D03*
Y1686180D03*
X345079Y1691692D03*
Y1696417D03*
X352953Y1695629D03*
Y1700354D03*
X345079Y1705866D03*
Y1710590D03*
X352953Y1709803D03*
Y1714527D03*
X345079Y1720039D03*
Y1724763D03*
X352953Y1723976D03*
Y1728700D03*
X495079Y1677519D03*
Y1682244D03*
Y1691692D03*
Y1696417D03*
Y1705866D03*
Y1710590D03*
Y1720039D03*
Y1724763D03*
X510827Y1677519D03*
X502953Y1681456D03*
X510827Y1682244D03*
X502953Y1686180D03*
X510827Y1691692D03*
X502953Y1695629D03*
X510827Y1696417D03*
X502953Y1700354D03*
X510827Y1705866D03*
X502953Y1709803D03*
X510827Y1710590D03*
X502953Y1714527D03*
X510827Y1720039D03*
X502953Y1723976D03*
X510827Y1724763D03*
X502953Y1728700D03*
X526575Y1677519D03*
X518701Y1681456D03*
X526575Y1682244D03*
X534449Y1681456D03*
X518701Y1686180D03*
X534449D03*
X526575Y1691692D03*
X518701Y1695629D03*
X526575Y1696417D03*
X534449Y1695629D03*
X518701Y1700354D03*
X534449D03*
X526575Y1705866D03*
X518701Y1709803D03*
X526575Y1710590D03*
X534449Y1709803D03*
X518701Y1714527D03*
X534449D03*
X526575Y1720039D03*
X518701Y1723976D03*
X526575Y1724763D03*
X534449Y1723976D03*
X518701Y1728700D03*
X534449D03*
X542323Y1677519D03*
Y1682244D03*
X550197Y1681456D03*
Y1686180D03*
X542323Y1691692D03*
Y1696417D03*
X550197Y1695629D03*
Y1700354D03*
X542323Y1705866D03*
Y1710590D03*
X550197Y1709803D03*
Y1714527D03*
X542323Y1720039D03*
Y1724763D03*
X550197Y1723976D03*
Y1728700D03*
X562008Y1677519D03*
Y1682244D03*
Y1691692D03*
Y1696417D03*
Y1705866D03*
Y1710590D03*
Y1720039D03*
Y1724763D03*
X577756Y1677519D03*
X569882Y1681456D03*
X577756Y1682244D03*
X569882Y1686180D03*
X577756Y1691692D03*
X569882Y1695629D03*
X577756Y1696417D03*
X569882Y1700354D03*
X577756Y1705866D03*
X569882Y1709803D03*
X577756Y1710590D03*
X569882Y1714527D03*
X577756Y1720039D03*
X569882Y1723976D03*
X577756Y1724763D03*
X569882Y1728700D03*
X593504Y1677519D03*
X585630Y1681456D03*
X593504Y1682244D03*
X585630Y1686180D03*
X593504Y1691692D03*
X585630Y1695629D03*
X593504Y1696417D03*
X585630Y1700354D03*
X593504Y1705866D03*
X585630Y1709803D03*
X593504Y1710590D03*
X585630Y1714527D03*
X593504Y1720039D03*
X585630Y1723976D03*
X593504Y1724763D03*
X585630Y1728700D03*
X609252Y1677519D03*
X601378Y1681456D03*
X609252Y1682244D03*
X601378Y1686180D03*
X609252Y1691692D03*
X601378Y1695629D03*
X609252Y1696417D03*
X601378Y1700354D03*
X609252Y1705866D03*
X601378Y1709803D03*
X609252Y1710590D03*
X601378Y1714527D03*
X609252Y1720039D03*
X601378Y1723976D03*
X609252Y1724763D03*
X601378Y1728700D03*
X617126Y1681456D03*
Y1686180D03*
Y1695629D03*
Y1700354D03*
Y1709803D03*
Y1714527D03*
Y1723976D03*
Y1728700D03*
X1238780Y1677519D03*
Y1682244D03*
X1246654Y1681456D03*
Y1686180D03*
X1238780Y1691692D03*
Y1696417D03*
X1246654Y1695629D03*
Y1700354D03*
X1238780Y1705866D03*
Y1710590D03*
X1246654Y1709803D03*
Y1714527D03*
X1238780Y1720039D03*
Y1724763D03*
X1246654Y1723976D03*
Y1728700D03*
X1254528Y1677519D03*
Y1682244D03*
X1262402Y1681456D03*
Y1686180D03*
X1254528Y1691692D03*
Y1696417D03*
X1262402Y1695629D03*
Y1700354D03*
X1254528Y1705866D03*
Y1710590D03*
X1262402Y1709803D03*
Y1714527D03*
X1254528Y1720039D03*
Y1724763D03*
X1262402Y1723976D03*
Y1728700D03*
X1270276Y1677519D03*
Y1682244D03*
X1278150Y1681456D03*
Y1686180D03*
X1270276Y1691692D03*
Y1696417D03*
X1278150Y1695629D03*
Y1700354D03*
X1270276Y1705866D03*
Y1710590D03*
X1278150Y1709803D03*
Y1714527D03*
X1270276Y1720039D03*
Y1724763D03*
X1278150Y1723976D03*
Y1728700D03*
X1286024Y1677519D03*
Y1682244D03*
X1293898Y1681456D03*
Y1686180D03*
X1286024Y1691692D03*
Y1696417D03*
X1293898Y1695629D03*
Y1700354D03*
X1286024Y1705866D03*
Y1710590D03*
X1293898Y1709803D03*
Y1714527D03*
X1286024Y1720039D03*
Y1724763D03*
X1293898Y1723976D03*
Y1728700D03*
X1305709Y1677519D03*
Y1682244D03*
X1313583Y1681456D03*
Y1686180D03*
X1305709Y1691692D03*
Y1696417D03*
X1313583Y1695629D03*
Y1700354D03*
X1305709Y1705866D03*
Y1710590D03*
X1313583Y1709803D03*
Y1714527D03*
X1305709Y1720039D03*
Y1724763D03*
X1313583Y1723976D03*
Y1728700D03*
X1321457Y1677519D03*
Y1682244D03*
X1329331Y1681456D03*
Y1686180D03*
X1321457Y1691692D03*
Y1696417D03*
X1329331Y1695629D03*
Y1700354D03*
X1321457Y1705866D03*
Y1710590D03*
X1329331Y1709803D03*
Y1714527D03*
X1321457Y1720039D03*
Y1724763D03*
X1329331Y1723976D03*
Y1728700D03*
X1337205Y1677519D03*
Y1682244D03*
X1345079Y1681456D03*
Y1686180D03*
X1337205Y1691692D03*
Y1696417D03*
X1345079Y1695629D03*
Y1700354D03*
X1337205Y1705866D03*
Y1710590D03*
X1345079Y1709803D03*
Y1714527D03*
X1337205Y1720039D03*
Y1724763D03*
X1345079Y1723976D03*
Y1728700D03*
X1352953Y1677519D03*
Y1682244D03*
X1360827Y1681456D03*
Y1686180D03*
X1352953Y1691692D03*
Y1696417D03*
X1360827Y1695629D03*
Y1700354D03*
X1352953Y1705866D03*
Y1710590D03*
X1360827Y1709803D03*
Y1714527D03*
X1352953Y1720039D03*
Y1724763D03*
X1360827Y1723976D03*
Y1728700D03*
X1502953Y1677519D03*
Y1682244D03*
X1510827Y1681456D03*
Y1686180D03*
X1502953Y1691692D03*
Y1696417D03*
X1510827Y1695629D03*
Y1700354D03*
X1502953Y1705866D03*
Y1710590D03*
X1510827Y1709803D03*
Y1714527D03*
X1502953Y1720039D03*
Y1724763D03*
X1510827Y1723976D03*
Y1728700D03*
X1518701Y1677519D03*
Y1682244D03*
X1526575Y1681456D03*
Y1686180D03*
X1518701Y1691692D03*
Y1696417D03*
X1526575Y1695629D03*
Y1700354D03*
X1518701Y1705866D03*
Y1710590D03*
X1526575Y1709803D03*
Y1714527D03*
X1518701Y1720039D03*
Y1724763D03*
X1526575Y1723976D03*
Y1728700D03*
X1534449Y1677519D03*
Y1682244D03*
X1542323Y1681456D03*
Y1686180D03*
X1534449Y1691692D03*
Y1696417D03*
X1542323Y1695629D03*
Y1700354D03*
X1534449Y1705866D03*
Y1710590D03*
X1542323Y1709803D03*
Y1714527D03*
X1534449Y1720039D03*
Y1724763D03*
X1542323Y1723976D03*
Y1728700D03*
X1550197Y1677519D03*
Y1682244D03*
X1558071Y1681456D03*
Y1686180D03*
X1550197Y1691692D03*
Y1696417D03*
X1558071Y1695629D03*
Y1700354D03*
X1550197Y1705866D03*
Y1710590D03*
X1558071Y1709803D03*
Y1714527D03*
X1550197Y1720039D03*
Y1724763D03*
X1558071Y1723976D03*
Y1728700D03*
X1569882Y1677519D03*
Y1682244D03*
Y1691692D03*
Y1696417D03*
Y1705866D03*
Y1710590D03*
Y1720039D03*
Y1724763D03*
X1585630Y1677519D03*
X1577756Y1681456D03*
X1585630Y1682244D03*
X1577756Y1686180D03*
X1585630Y1691692D03*
X1577756Y1695629D03*
X1585630Y1696417D03*
X1577756Y1700354D03*
X1585630Y1705866D03*
X1577756Y1709803D03*
X1585630Y1710590D03*
X1577756Y1714527D03*
X1585630Y1720039D03*
X1577756Y1723976D03*
X1585630Y1724763D03*
X1577756Y1728700D03*
X1601378Y1677519D03*
X1593504Y1681456D03*
X1601378Y1682244D03*
X1593504Y1686180D03*
X1601378Y1691692D03*
X1593504Y1695629D03*
X1601378Y1696417D03*
X1593504Y1700354D03*
X1601378Y1705866D03*
X1593504Y1709803D03*
X1601378Y1710590D03*
X1593504Y1714527D03*
X1601378Y1720039D03*
X1593504Y1723976D03*
X1601378Y1724763D03*
X1593504Y1728700D03*
X1617126Y1677519D03*
X1609252Y1681456D03*
X1617126Y1682244D03*
X1609252Y1686180D03*
X1617126Y1691692D03*
X1609252Y1695629D03*
X1617126Y1696417D03*
X1609252Y1700354D03*
X1617126Y1705866D03*
X1609252Y1709803D03*
X1617126Y1710590D03*
X1609252Y1714527D03*
X1617126Y1720039D03*
X1609252Y1723976D03*
X1617126Y1724763D03*
X1609252Y1728700D03*
X1625000Y1681456D03*
Y1686180D03*
Y1695629D03*
Y1700354D03*
Y1709803D03*
Y1714527D03*
Y1723976D03*
Y1728700D03*
G54D36*
X159474Y1328627D03*
X183847Y1328652D03*
X208247D03*
X275289Y583576D03*
Y607735D03*
Y631889D03*
Y656043D03*
X270252Y676260D03*
Y700414D03*
X387897Y1242785D03*
X412297D03*
X436619D03*
X461019D03*
X485419D03*
X673093Y1328652D03*
X697466Y1328677D03*
X721866D03*
X1100800Y259362D03*
X1100700Y283662D03*
X1131100Y1364962D03*
X1155500D03*
X1179900D03*
X1364038Y1242785D03*
X1388438D03*
X1412760D03*
X1437160D03*
X1461560D03*
X1577000Y599762D03*
Y624262D03*
Y648762D03*
Y673162D03*
Y697662D03*
Y722162D03*
X1634259Y1362248D03*
X1658632Y1362273D03*
X1683032D03*
G54D90*
X1010362Y1637176D03*
Y1663160D03*
X1036450Y1637260D03*
Y1663244D03*
G54D27*
X60303Y20354D03*
X174685Y637367D03*
X174393Y668511D03*
X205159Y1430034D03*
X312921Y24291D03*
X393067Y1354446D03*
X422833D03*
X453169D03*
X468443Y1379662D03*
X482543Y1353962D03*
X505185Y41142D03*
X526478Y1439952D03*
X718638Y1429579D03*
X757803Y45079D03*
X922441Y237697D03*
X929331Y160413D03*
X1077638Y133866D03*
X1178470Y1466363D03*
X1369208Y1353946D03*
X1398974D03*
X1429310D03*
X1444043Y1379362D03*
X1459076Y1353946D03*
X1502956Y1439530D03*
X1534712Y20354D03*
X1682882Y618174D03*
Y669109D03*
X1679944Y1463655D03*
X1769790Y194789D03*
X1787330Y24291D03*
X1799350Y194789D03*
X1836248Y269763D03*
Y299056D03*
G54D55*
X417650Y1635132D03*
X410170D03*
X417580Y1643304D03*
X410100D03*
X937566Y382223D03*
X933830Y967442D03*
X941310D03*
X945046Y382223D03*
X1026552Y405913D03*
X1034032D03*
G54D91*
X1041500Y382122D03*
Y389602D03*
G54D73*
X769895Y281705D03*
Y279146D03*
Y276587D03*
Y274028D03*
Y271469D03*
Y286823D03*
Y284264D03*
X764977Y298790D03*
Y296231D03*
Y311585D03*
Y309026D03*
Y306467D03*
Y303908D03*
Y301349D03*
X792895Y271469D03*
Y274028D03*
Y276587D03*
Y279146D03*
Y281705D03*
Y284264D03*
Y286823D03*
X787977Y296231D03*
Y298790D03*
Y301349D03*
Y303908D03*
Y306467D03*
Y309026D03*
Y311585D03*
X812499Y299070D03*
Y296511D03*
Y311865D03*
Y309306D03*
Y306747D03*
Y304188D03*
Y301629D03*
X822500Y281507D03*
Y278948D03*
Y276389D03*
Y273830D03*
Y271271D03*
Y286625D03*
Y284066D03*
X835499Y296511D03*
Y299070D03*
Y301629D03*
Y304188D03*
Y306747D03*
Y309306D03*
Y311865D03*
X845500Y271271D03*
Y273830D03*
Y276389D03*
Y278948D03*
Y281507D03*
Y284066D03*
Y286625D03*
G54D82*
X859100Y769165D03*
Y765425D03*
Y761685D03*
X849454D03*
Y769165D03*
G54D28*
X57544Y397012D03*
X53738Y396986D03*
X60761Y435475D03*
X56722Y435542D03*
X61775Y1244977D03*
X65397Y381644D03*
X69998Y381753D03*
X73281Y693127D03*
X91123Y1244051D03*
X94700Y1539788D03*
X95876Y690719D03*
X125760Y653056D03*
X135950Y1254658D03*
X159197Y1234212D03*
X173865Y1240342D03*
X201360Y669758D03*
X219272Y759901D03*
X241160Y1245008D03*
X254122Y33886D03*
X246220Y33878D03*
X250220D03*
X242220D03*
X246859Y60602D03*
X250859Y60612D03*
X250457Y758101D03*
X254477Y758211D03*
X273046Y720185D03*
Y729980D03*
X273246Y749680D03*
X286720Y42878D03*
X277046Y720185D03*
X281046Y729980D03*
X277046D03*
Y740480D03*
X281046D03*
X285046D03*
X281046Y749480D03*
X277046D03*
X285046D03*
X275639Y863963D03*
X274693Y1252002D03*
X291520Y15253D03*
X302720Y42878D03*
X294720D03*
X298211Y177795D03*
X290953Y714341D03*
X292706Y749324D03*
X300839Y1308072D03*
X316345Y205140D03*
X318158Y228503D03*
X316656Y730304D03*
X320656D03*
X312656Y723304D03*
X307967Y723360D03*
X317967Y749831D03*
X334546Y738814D03*
X332656Y723304D03*
X324656D03*
X351946Y722988D03*
X348037Y722991D03*
X344440Y742288D03*
X355946Y722991D03*
X366902Y749324D03*
X374902D03*
X387810Y1660548D03*
X391880Y1660508D03*
X436514Y1636433D03*
X440280Y1636503D03*
X499590Y88258D03*
X498730Y122638D03*
X498630Y143248D03*
X503100Y81208D03*
X507310Y81178D03*
X503270Y122648D03*
X507320Y122698D03*
X503290Y143238D03*
X507360Y143208D03*
X525900Y104316D03*
X548609Y35378D03*
X545450Y88843D03*
X541370D03*
X563100Y52698D03*
X581520Y52778D03*
X576200Y52738D03*
X571580Y52698D03*
X598405D03*
X594097D03*
X592076Y747981D03*
X610970Y52708D03*
X606330Y52698D03*
X602350D03*
X614750Y750481D03*
X603276Y747981D03*
X620097Y52698D03*
X631060Y48808D03*
X619090Y42808D03*
X620814Y155492D03*
X617008Y155466D03*
X645083Y33622D03*
X635000Y51378D03*
X639000D03*
X633603Y163212D03*
X644335Y1253309D03*
X654196Y1244943D03*
X670080Y52698D03*
X678050D03*
X674080D03*
X667347Y758401D03*
X672537Y758461D03*
X694400Y52698D03*
X681980D03*
X682588Y87353D03*
X682440Y115886D03*
X689663Y404415D03*
X684705Y1248476D03*
X698597Y52698D03*
X707597D03*
X711867Y52738D03*
X702790Y52688D03*
X712000Y72178D03*
X700960Y128218D03*
X710433Y412375D03*
X702062Y1254510D03*
X712298Y1605818D03*
X708175Y1605827D03*
X704219Y1634867D03*
X705083Y1661009D03*
X728000Y78378D03*
X719967Y72178D03*
X723957D03*
X715990D03*
X714427Y1247591D03*
X720112Y1604249D03*
X731069Y1230732D03*
X730328Y1254514D03*
X734111Y1254535D03*
X744022Y1246023D03*
X748178Y404935D03*
X772570Y1246028D03*
X762670Y1666505D03*
X791685Y1254410D03*
X808220Y140078D03*
X808843Y425645D03*
X803116Y1244133D03*
X821120Y139478D03*
X819401Y1253010D03*
X820110Y1243628D03*
X841720Y212878D03*
X837500Y223168D03*
X840651Y1236902D03*
X847271Y1253739D03*
X849767Y1246806D03*
X922320Y1663878D03*
X918300Y1663916D03*
X932487Y486199D03*
X928958Y484554D03*
X939970Y520204D03*
X924761Y520055D03*
X928393Y518607D03*
X934020Y991088D03*
X938220Y1663778D03*
X926120Y1663878D03*
X933979Y1663843D03*
X929979Y1663878D03*
X943369Y505094D03*
X946100Y1663816D03*
X942100D03*
X950100D03*
X953900D03*
X964347Y503807D03*
X968355Y503754D03*
X965570Y1559276D03*
X985445Y175599D03*
X988219Y412912D03*
X984254D03*
X1004189Y401214D03*
X1012942Y295086D03*
X1008942D03*
X1017720Y307878D03*
X1013720D03*
X1009334Y401183D03*
X1013105Y401226D03*
X1037000Y293528D03*
X1052504Y1254177D03*
X1082030Y1254368D03*
X1111904Y1254211D03*
X1135339Y1234212D03*
X1135687Y1585254D03*
X1131687D03*
X1149903Y1247350D03*
X1145687Y1585254D03*
X1141687D03*
X1151687D03*
X1153467Y589038D03*
X1166077Y763341D03*
X1165095Y1585254D03*
X1155687D03*
X1161095D03*
X1160310Y1628276D03*
X1177677Y761011D03*
X1172649Y1254378D03*
X1179563Y1247507D03*
X1175095Y1585254D03*
X1171095D03*
X1200497Y765131D03*
X1195097D03*
Y756223D03*
X1199597Y756195D03*
X1199679Y1254665D03*
X1208537Y748321D03*
X1212537D03*
X1209247Y765121D03*
X1212937Y756821D03*
X1208937D03*
X1204497Y765131D03*
X1209315Y1247754D03*
X1223793Y1236902D03*
X1230681Y1246806D03*
X1223793Y1243902D03*
X1230681Y1254694D03*
X1242398Y751333D03*
X1246260Y760481D03*
X1262383Y103676D03*
X1260514Y221398D03*
X1259998Y732533D03*
X1263787Y732531D03*
X1252847Y745511D03*
X1250260Y760481D03*
X1276345Y99646D03*
X1279485Y110541D03*
X1274257Y740581D03*
X1276980Y1304133D03*
X1275856Y1352563D03*
X1272346D03*
X1291704Y103247D03*
X1295807Y112109D03*
X1295947Y732241D03*
X1289817Y741086D03*
X1303220Y107578D03*
X1310150Y129120D03*
X1309228Y122084D03*
X1314269Y122129D03*
X1303728Y127306D03*
X1300317Y737411D03*
X1308847Y749811D03*
X1305277D03*
X1328946Y131296D03*
X1319288Y122118D03*
X1327428Y123293D03*
X1317891Y129119D03*
X1323493Y129246D03*
X1322477Y176192D03*
X1330773Y198039D03*
X1322522Y189986D03*
X1321816Y726185D03*
X1330328Y738658D03*
X1320032Y749811D03*
X1316307D03*
X1332886Y126223D03*
X1336930Y124223D03*
X1334814Y198039D03*
X1335120Y209035D03*
X1338495Y749317D03*
X1334641Y749525D03*
X1445018Y724504D03*
X1458818D03*
X1449118D03*
X1453218D03*
X1459431Y1395911D03*
X1468947Y738651D03*
X1470656Y749317D03*
X1474656D03*
X1463249Y1395911D03*
X1482751Y749318D03*
X1502396Y731343D03*
X1507016Y734482D03*
X1499245Y749781D03*
X1494963Y749678D03*
X1510437Y313841D03*
X1521975Y749781D03*
X1517575D03*
X1534000Y126878D03*
X1527185Y749781D03*
X1561890Y198768D03*
X1562890Y240438D03*
X1573507Y749601D03*
X1577507D03*
X1590915Y765721D03*
X1582017Y893099D03*
Y907761D03*
X1602650Y1254739D03*
Y1247536D03*
X1616114Y1254060D03*
X1631545Y1245059D03*
X1654143Y1250701D03*
X1661120Y614178D03*
X1675414Y1254060D03*
X1690560Y427128D03*
X1699720Y490378D03*
X1694339Y491294D03*
X1702067Y695981D03*
X1705029Y1226326D03*
X1705013Y1253905D03*
X1690518Y1248096D03*
X1712820Y172296D03*
X1705720Y490378D03*
X1711720D03*
X1705896Y706463D03*
X1706017Y695981D03*
X1713606Y710953D03*
X1709013Y1253905D03*
X1705803Y1246953D03*
X1720183Y1249890D03*
X1734714Y1254160D03*
X1749690Y1245402D03*
X1769900Y40225D03*
X1762075D03*
X1770566Y300475D03*
X1764680Y306058D03*
X1764514Y1254060D03*
X1773791Y31370D03*
X1777754Y40385D03*
X1781990Y40271D03*
X1773554Y40225D03*
X1774537Y300560D03*
X1779319Y303696D03*
X1778789Y1247161D03*
X1787706Y50056D03*
X1791706D03*
X1797417Y1237906D03*
Y1244906D03*
X1816360Y1237777D03*
X1816612Y1253601D03*
X1810954Y1252880D03*
G54D46*
X230906Y1734212D03*
X297835D03*
X495079D03*
X562008D03*
X1238780D03*
X1305709D03*
X1502953D03*
X1569882D03*
G54D64*
X676508Y145866D03*
X1881720Y988279D03*
X1886720Y1001463D03*
X1876720D03*
X1875836Y1303980D03*
X1885836D03*
X1880836Y1317164D03*
X1881211Y1350983D03*
X1886211Y1364167D03*
X1876211D03*
X1876165Y1669023D03*
X1886165D03*
X1881165Y1682207D03*
X1902608Y988322D03*
X1897608Y1001506D03*
X1898086Y1305044D03*
X1903086Y1318228D03*
X1902682Y1351295D03*
X1897682Y1364479D03*
X1902402Y1683256D03*
X1897402Y1670072D03*
X1907608Y1001506D03*
X1908086Y1305044D03*
X1907682Y1364479D03*
X1907402Y1670072D03*
X1930200Y1349548D03*
X1935200Y1362732D03*
X1925200D03*
X1929695Y1683220D03*
X1924695Y1670036D03*
X1934695D03*
X1951178Y1349597D03*
X1946178Y1362781D03*
X1950484Y1683497D03*
X1945484Y1670313D03*
X1967697Y1362790D03*
X1956178Y1362781D03*
X1966555Y1669946D03*
X1955484Y1670313D03*
X1972697Y1349606D03*
X1977697Y1362790D03*
X1976555Y1669946D03*
X1971555Y1683130D03*
X1993618Y1349897D03*
X1988618Y1363081D03*
X1998618D03*
X1998147Y1669691D03*
X1988147D03*
X1993147Y1682875D03*
G54D37*
X163527Y1351890D03*
Y1377086D03*
X201927Y1351890D03*
Y1377086D03*
X349753Y1286498D03*
Y1311694D03*
X411380Y1274780D03*
Y1299976D03*
X447551Y1274792D03*
Y1299988D03*
X510022Y1286306D03*
Y1311502D03*
X677107Y1351915D03*
Y1377111D03*
X716004Y1351915D03*
Y1377111D03*
X1136799Y1389120D03*
Y1414316D03*
X1175696Y1389120D03*
Y1414316D03*
X1326294Y1287458D03*
Y1312654D03*
X1387521Y1274280D03*
Y1299476D03*
X1423692Y1274292D03*
Y1299488D03*
X1486163Y1286306D03*
Y1311502D03*
X1638273Y1384661D03*
Y1409857D03*
X1677170Y1384661D03*
Y1409857D03*
G54D19*
X40120Y744554D03*
Y1000853D03*
Y1287664D03*
X69820Y744554D03*
Y1000853D03*
Y1287664D03*
X99520Y744554D03*
Y1000853D03*
Y1287664D03*
X129220Y744554D03*
Y1000853D03*
Y1287664D03*
X158920Y744554D03*
Y1000853D03*
Y1287664D03*
X188620Y744554D03*
Y1000853D03*
Y1287664D03*
X218320Y744554D03*
Y1000853D03*
Y1287664D03*
X248020Y744554D03*
Y1000853D03*
Y1287664D03*
X633320Y744554D03*
Y1000853D03*
Y1287664D03*
X663020Y744554D03*
Y1000853D03*
Y1287664D03*
X692720Y744554D03*
Y1000853D03*
Y1287664D03*
X722420Y744554D03*
Y1000853D03*
Y1287664D03*
X752120Y744554D03*
Y1000853D03*
Y1287664D03*
X781820Y744554D03*
Y1000853D03*
Y1287664D03*
X811520Y744554D03*
Y1000853D03*
Y1287664D03*
X841220Y744554D03*
Y1000853D03*
Y1287664D03*
X1016262Y744554D03*
Y1000853D03*
Y1287664D03*
X1045962Y744554D03*
Y1000853D03*
Y1287664D03*
X1075662Y744554D03*
Y1000853D03*
Y1287664D03*
X1105362Y744554D03*
Y1000853D03*
Y1287664D03*
X1135062Y744554D03*
Y1000853D03*
Y1287664D03*
X1164762Y744554D03*
Y1000853D03*
Y1287664D03*
X1194462Y744554D03*
Y1000853D03*
Y1287664D03*
X1224162Y744554D03*
Y1000853D03*
Y1287664D03*
X1609462Y744554D03*
Y1000853D03*
Y1287664D03*
X1639162Y744554D03*
Y1000853D03*
Y1287664D03*
X1668862Y744554D03*
Y1000853D03*
Y1287664D03*
X1698562Y744554D03*
Y1000853D03*
Y1287664D03*
X1728262Y744554D03*
Y1000853D03*
Y1287664D03*
X1757962Y744554D03*
Y1000853D03*
Y1287664D03*
X1787662Y744554D03*
Y1000853D03*
Y1287664D03*
X1817362Y744554D03*
Y1000853D03*
Y1287664D03*
G54D47*
X277098Y185236D03*
X322500Y1391830D03*
X395208Y185236D03*
X537477Y1395413D03*
X1133779Y1653543D03*
X1298642Y1391830D03*
X1513618Y1395413D03*
G54D74*
X771724Y763455D03*
Y758337D03*
X778724D03*
Y760896D03*
Y763455D03*
G54D83*
X900196Y175197D03*
X944684Y155216D03*
G54D56*
X441043Y1698268D03*
X1416437Y1698267D03*
G54D38*
X164686Y394320D03*
D03*
Y391170D03*
Y397470D03*
X753835Y309670D03*
Y306520D03*
Y312820D03*
Y309670D03*
X1288020Y267477D03*
Y270627D03*
G54D65*
X673054Y432187D03*
X669904D03*
X673054Y460533D03*
X669904D03*
X695101Y441636D03*
Y444785D03*
Y451084D03*
Y447935D03*
X698251Y441636D03*
Y444785D03*
Y451084D03*
Y447935D03*
X704550Y466832D03*
X701400D03*
X717148Y438486D03*
X713998D03*
X717148Y444785D03*
X713998D03*
X717148Y441636D03*
X713998D03*
X717148Y447935D03*
X713998D03*
X717148Y451084D03*
X713998D03*
X717148Y454234D03*
X713998D03*
G54D29*
X57544Y399979D03*
X53738Y399953D03*
X60761Y438442D03*
X56722Y438509D03*
X61775Y1247944D03*
X65397Y384611D03*
X69998Y384720D03*
X73281Y696094D03*
X91123Y1247018D03*
X94700Y1542755D03*
X95876Y693686D03*
X125760Y656023D03*
X135950Y1257625D03*
X159197Y1237179D03*
X173865Y1243309D03*
X201360Y672725D03*
X219272Y762868D03*
X241160Y1247975D03*
X254122Y36853D03*
X246220Y36845D03*
X250220D03*
X242220D03*
X246859Y63569D03*
X250859Y63579D03*
X250457Y761068D03*
X254477Y761178D03*
X273046Y723152D03*
Y732947D03*
X273246Y752647D03*
X286720Y45845D03*
X281046Y732947D03*
X277046Y723152D03*
Y732947D03*
Y743447D03*
X281046D03*
X285046D03*
X281046Y752447D03*
X277046D03*
X285046D03*
X275639Y866930D03*
X274693Y1254969D03*
X291520Y18220D03*
X302720Y45845D03*
X294720D03*
X298211Y180762D03*
X290953Y717308D03*
X292706Y752291D03*
X300839Y1311039D03*
X316345Y208107D03*
X318158Y231470D03*
X316656Y733271D03*
X320656D03*
X312656Y726271D03*
X307967Y726327D03*
X317967Y752798D03*
X332656Y726271D03*
X324656D03*
X334546Y741781D03*
X351946Y725955D03*
X348037Y725958D03*
X344440Y745255D03*
X355946Y725958D03*
X366902Y752291D03*
X374902D03*
X387810Y1663515D03*
X391880Y1663475D03*
X436514Y1639400D03*
X440280Y1639470D03*
X499590Y91225D03*
X498730Y125605D03*
X498630Y146215D03*
X503100Y84175D03*
X507310Y84145D03*
X503270Y125615D03*
X507320Y125665D03*
X503290Y146205D03*
X507360Y146175D03*
X525900Y107283D03*
X548609Y38345D03*
X545450Y91810D03*
X541370D03*
X563100Y55665D03*
X581520Y55745D03*
X576200Y55705D03*
X571580Y55665D03*
X598405D03*
X594097D03*
X592076Y750948D03*
X610970Y55675D03*
X606330Y55665D03*
X602350D03*
X614750Y753448D03*
X603276Y750948D03*
X620097Y55665D03*
X631060Y51775D03*
X619090Y45775D03*
X620814Y158459D03*
X617008Y158433D03*
X645083Y36589D03*
X635000Y54345D03*
X639000D03*
X633603Y166179D03*
X644335Y1256276D03*
X654196Y1247910D03*
X670080Y55665D03*
X678050D03*
X674080D03*
X667347Y761368D03*
X672537Y761428D03*
X694400Y55665D03*
X681980D03*
X682588Y90320D03*
X682440Y118853D03*
X689663Y407382D03*
X684705Y1251443D03*
X698597Y55665D03*
X707597D03*
X711867Y55705D03*
X702790Y55655D03*
X712000Y75145D03*
X700960Y131185D03*
X710433Y415342D03*
X702062Y1257477D03*
X712298Y1608785D03*
X708175Y1608794D03*
X704219Y1637834D03*
X705083Y1663976D03*
X728000Y81345D03*
X719967Y75145D03*
X723957D03*
X715990D03*
X714427Y1250558D03*
X720112Y1607216D03*
X731069Y1233699D03*
X730328Y1257481D03*
X734111Y1257502D03*
X744022Y1248990D03*
X748178Y407902D03*
X772570Y1248995D03*
X762670Y1669472D03*
X791685Y1257377D03*
X808220Y143045D03*
X808843Y428612D03*
X803116Y1247100D03*
X821120Y142445D03*
X819401Y1255977D03*
X820110Y1246595D03*
X841720Y215845D03*
X837500Y226135D03*
X840651Y1239869D03*
X847271Y1256706D03*
X849767Y1249773D03*
X922320Y1666845D03*
X918300Y1666883D03*
X932487Y489166D03*
X928958Y487521D03*
X939970Y523171D03*
X924761Y523022D03*
X928393Y521574D03*
X934020Y994055D03*
X938220Y1666745D03*
X926120Y1666845D03*
X933979Y1666810D03*
X929979Y1666845D03*
X943369Y508061D03*
X946100Y1666783D03*
X942100D03*
X950100D03*
X953900D03*
X964347Y506774D03*
X968355Y506721D03*
X965570Y1562243D03*
X985445Y178566D03*
X988219Y415879D03*
X984254D03*
X1004189Y404181D03*
X1012942Y298053D03*
X1008942D03*
X1017720Y310845D03*
X1013720D03*
X1009334Y404150D03*
X1013105Y404193D03*
X1037000Y296495D03*
X1052504Y1257144D03*
X1082030Y1257335D03*
X1111904Y1257178D03*
X1135339Y1237179D03*
X1135687Y1588221D03*
X1131687D03*
X1149903Y1250317D03*
X1145687Y1588221D03*
X1141687D03*
X1151687D03*
X1153467Y592005D03*
X1166077Y766308D03*
X1165095Y1588221D03*
X1155687D03*
X1161095D03*
X1160310Y1631243D03*
X1177677Y763978D03*
X1172649Y1257345D03*
X1179563Y1250474D03*
X1175095Y1588221D03*
X1171095D03*
X1200497Y768098D03*
X1195097D03*
Y759190D03*
X1199597Y759162D03*
X1199679Y1257632D03*
X1208537Y751288D03*
X1212537D03*
X1209247Y768088D03*
X1212937Y759788D03*
X1208937D03*
X1204497Y768098D03*
X1209315Y1250721D03*
X1223793Y1239869D03*
X1230681Y1249773D03*
X1223793Y1246869D03*
X1230681Y1257661D03*
X1242398Y754300D03*
X1246260Y763448D03*
X1262383Y106643D03*
X1260514Y224365D03*
X1259998Y735500D03*
X1263787Y735498D03*
X1252847Y748478D03*
X1250260Y763448D03*
X1276345Y102613D03*
X1279485Y113508D03*
X1274257Y743548D03*
X1276980Y1307100D03*
X1275856Y1355530D03*
X1272346D03*
X1295807Y115076D03*
X1291704Y106214D03*
X1295947Y735208D03*
X1289817Y744053D03*
X1303220Y110545D03*
X1310150Y132087D03*
X1309228Y125051D03*
X1314269Y125096D03*
X1303728Y130273D03*
X1308847Y752778D03*
X1305277D03*
X1300317Y740378D03*
X1328946Y134263D03*
X1319288Y125085D03*
X1327428Y126260D03*
X1317891Y132086D03*
X1323493Y132213D03*
X1322477Y179159D03*
X1330773Y201006D03*
X1322522Y192953D03*
X1321816Y729152D03*
X1320032Y752778D03*
X1316307D03*
X1330328Y741625D03*
X1332886Y129190D03*
X1336930Y127190D03*
X1334814Y201006D03*
X1335120Y212002D03*
X1338495Y752284D03*
X1334641Y752492D03*
X1445018Y727471D03*
X1458818D03*
X1449118D03*
X1453218D03*
X1459431Y1398878D03*
X1470656Y752284D03*
X1474656D03*
X1468947Y741618D03*
X1463249Y1398878D03*
X1482751Y752285D03*
X1502396Y734310D03*
X1507016Y737449D03*
X1499245Y752748D03*
X1494963Y752645D03*
X1510437Y316808D03*
X1521975Y752748D03*
X1517575D03*
X1534000Y129845D03*
X1527185Y752748D03*
X1561890Y201735D03*
X1562890Y243405D03*
X1573507Y752568D03*
X1577507D03*
X1590915Y768688D03*
X1582017Y896066D03*
Y910728D03*
X1602650Y1257706D03*
Y1250503D03*
X1616114Y1257027D03*
X1631545Y1248026D03*
X1654143Y1253668D03*
X1661120Y617145D03*
X1675414Y1257027D03*
X1690560Y430095D03*
X1699720Y493345D03*
X1694339Y494261D03*
X1702067Y698948D03*
X1705029Y1229293D03*
X1705013Y1256872D03*
X1690518Y1251063D03*
X1712820Y175263D03*
X1705720Y493345D03*
X1711720D03*
X1706017Y698948D03*
X1705896Y709430D03*
X1713606Y713920D03*
X1709013Y1256872D03*
X1705803Y1249920D03*
X1720183Y1252857D03*
X1734714Y1257127D03*
X1749690Y1248369D03*
X1769900Y43192D03*
X1762075D03*
X1770566Y303442D03*
X1764680Y309025D03*
X1764514Y1257027D03*
X1773791Y34337D03*
X1777754Y43352D03*
X1781990Y43238D03*
X1773554Y43192D03*
X1774537Y303527D03*
X1779319Y306663D03*
X1778789Y1250128D03*
X1787706Y53023D03*
X1791706D03*
X1797417Y1240873D03*
Y1247873D03*
X1816360Y1240744D03*
X1816612Y1256568D03*
X1810954Y1255847D03*
G54D92*
X1131715Y1532913D03*
X1175215D03*
G54D75*
X791280Y1704890D03*
X1066280D03*
G54D48*
X306772Y991220D03*
X350099Y811121D03*
X356063Y1171318D03*
X531240Y811121D03*
X525276Y1171318D03*
X574567Y991220D03*
X1282914D03*
X1326240Y811121D03*
X1332205Y1171318D03*
X1507382Y811121D03*
X1501418Y1171318D03*
X1550709Y991220D03*
G54D66*
X676203Y444785D03*
Y447935D03*
X685652Y413289D03*
Y416439D03*
X695101Y457384D03*
Y454234D03*
X701400Y444785D03*
Y441635D03*
X704550Y444785D03*
Y441635D03*
X707699Y457384D03*
Y454234D03*
X704550Y457384D03*
Y454234D03*
X701400Y457384D03*
Y454234D03*
X698251Y457384D03*
Y454234D03*
X710849Y457384D03*
Y454234D03*
X723447Y413289D03*
Y416439D03*
G54D93*
X1156378Y133866D03*
G54D39*
X174685Y647210D03*
X174393Y678354D03*
X195316Y1430034D03*
X383224Y1354446D03*
X412990D03*
X443326D03*
X458600Y1379662D03*
X472700Y1353962D03*
X526478Y1449795D03*
X708795Y1429579D03*
X1168627Y1466363D03*
X1359365Y1353946D03*
X1389131D03*
X1419467D03*
X1434200Y1379362D03*
X1449233Y1353946D03*
X1502956Y1449373D03*
X1670101Y1463655D03*
X1682882Y628017D03*
Y678952D03*
X1769790Y204632D03*
X1799350D03*
X1826405Y269763D03*
Y299056D03*
G54D57*
X450000Y278543D03*
X460000D03*
X470000D03*
X483500Y246362D03*
X480000Y278543D03*
X493500Y246362D03*
X490000Y278543D03*
X500000D03*
X510000D03*
X518563Y607067D03*
X508563D03*
X559236Y1441207D03*
X569236D03*
X688500Y1601900D03*
Y1611900D03*
X1041435Y143357D03*
Y153357D03*
X1056225Y143131D03*
Y153131D03*
X1099970Y1702570D03*
Y1712570D03*
X1689646Y115669D03*
X1679646D03*
X1689646Y125669D03*
Y135669D03*
X1679646Y125669D03*
Y135669D03*
X1689646Y145669D03*
Y155669D03*
X1679646Y145669D03*
Y155669D03*
X1689646Y165669D03*
X1679646D03*
X1689646Y175669D03*
X1771457Y1634646D03*
Y1644646D03*
G54D84*
X922441Y154311D03*
Y243799D03*
G54D67*
X688802Y438486D03*
X691952D03*
X688802Y441636D03*
X691952D03*
X688802Y444785D03*
X691952D03*
X688802Y454234D03*
X691952D03*
X688802Y447935D03*
X691952D03*
X688802Y451084D03*
X691952D03*
X707699Y444785D03*
X710849D03*
X707699Y441636D03*
X710849D03*
X707699Y447935D03*
X710849D03*
X707699Y451084D03*
X710849D03*
X729747Y432187D03*
X732897D03*
X729747Y460533D03*
X732897D03*
G54D94*
X1164858Y592327D03*
Y589827D03*
Y607327D03*
Y604827D03*
Y602327D03*
Y599827D03*
Y597327D03*
Y594827D03*
X1186058Y592327D03*
Y589827D03*
Y607327D03*
Y604827D03*
Y602327D03*
Y599827D03*
Y597327D03*
Y594827D03*
G54D85*
X928739Y323031D03*
G54D58*
X473500Y246362D03*
X498563Y607067D03*
X520000Y278543D03*
X549236Y1441207D03*
X688500Y1621900D03*
X1041435Y163357D03*
X1056225Y163131D03*
X1099970Y1722570D03*
X1679646Y175669D03*
X1771457Y1624646D03*
G54D76*
X793879Y194881D03*
X789942Y204724D03*
X793879Y214567D03*
X805690Y188976D03*
Y220472D03*
X817501Y194881D03*
Y214567D03*
X821438Y204724D03*
X916545Y309459D03*
X911494Y321653D03*
X916545Y333847D03*
X940933Y309459D03*
X928739Y304408D03*
Y338898D03*
X940933Y333847D03*
X945984Y321653D03*
X1045847Y194881D03*
X1041910Y204724D03*
X1045847Y214567D03*
X1069469Y194881D03*
X1057658Y188976D03*
X1069469Y214567D03*
X1057658Y220472D03*
X1073406Y204724D03*
G54D49*
X320561Y168009D03*
Y192509D03*
X366037Y1385515D03*
Y1410015D03*
X1338727Y1385105D03*
Y1409605D03*
G54D68*
X695101Y435336D03*
Y438486D03*
X685652Y476281D03*
Y479431D03*
X708300Y418750D03*
Y421900D03*
X701400Y435336D03*
Y438486D03*
X704550Y435336D03*
Y438486D03*
X698251Y435336D03*
Y438486D03*
X707699Y435336D03*
Y438486D03*
X710849Y435336D03*
Y438486D03*
X704550Y447935D03*
Y451085D03*
X701400Y447935D03*
Y451085D03*
X726597Y444785D03*
Y447935D03*
X723447Y476281D03*
Y479431D03*
G54D77*
X805690Y204724D03*
X1057658D03*
G54D59*
X493384Y101473D03*
X491284D03*
X493384Y98373D03*
X491284D03*
X485480Y107972D03*
X487580D03*
X485480Y111282D03*
X487580D03*
X520480Y98012D03*
X518380D03*
X520480Y94882D03*
X518380D03*
X564888Y1316279D03*
X566988D03*
X1375626Y256280D03*
X1377726D03*
X1375626Y252680D03*
X1377726D03*
X1539927Y1324555D03*
X1542027D03*
G54D95*
X1200450Y1247609D03*
X1263543Y141412D03*
X1261848Y146363D03*
X1264183Y154756D03*
X1266983Y151686D03*
G54D86*
X927154Y492103D03*
X918078Y495177D03*
X918212Y500777D03*
X926173Y512391D03*
G54D78*
X810850Y763874D03*
Y761315D03*
Y758756D03*
X818724D03*
Y761315D03*
Y763874D03*
X833120Y764094D03*
Y761535D03*
Y758976D03*
X840994D03*
Y761535D03*
Y764094D03*
G54D87*
X938780Y1714890D03*
G54D96*
X1202549Y1249708D03*
X1265642Y143511D03*
X1263947Y148462D03*
X1266282Y156855D03*
X1269082Y153785D03*
G54D69*
X705760Y-26500D03*
Y-16500D03*
D03*
Y-6500D03*
X730760Y-26500D03*
Y-16500D03*
D03*
Y-6500D03*
X822720Y3500D03*
Y13500D03*
D03*
Y23500D03*
X847720Y3500D03*
Y13500D03*
D03*
Y23500D03*
X973180Y-26500D03*
Y-16500D03*
D03*
Y-6500D03*
Y3500D03*
Y13500D03*
Y23500D03*
Y13500D03*
X998180Y-26500D03*
Y-16500D03*
D03*
Y-6500D03*
Y3500D03*
Y13500D03*
Y23500D03*
Y13500D03*
X1015152Y-26511D03*
Y-36511D03*
Y-26511D03*
Y-16511D03*
D03*
Y-6511D03*
D03*
Y3489D03*
D03*
Y13489D03*
D03*
Y23489D03*
X1040152Y-26511D03*
Y-36511D03*
Y-26511D03*
Y-16511D03*
D03*
Y-6511D03*
D03*
Y3489D03*
D03*
Y13489D03*
D03*
Y23489D03*
X1282572Y-36511D03*
Y-26511D03*
D03*
Y-16511D03*
D03*
Y-6511D03*
Y3489D03*
Y-6511D03*
Y3489D03*
Y13489D03*
Y23489D03*
Y13489D03*
X1307572Y-36511D03*
Y-26511D03*
D03*
Y-16511D03*
D03*
Y-6511D03*
Y3489D03*
Y-6511D03*
Y3489D03*
Y13489D03*
Y23489D03*
Y13489D03*
X1324471Y-26511D03*
Y-36511D03*
Y-26511D03*
Y-16511D03*
D03*
Y-6511D03*
D03*
Y3489D03*
D03*
Y13489D03*
D03*
Y23489D03*
X1349471Y-26511D03*
Y-36511D03*
Y-26511D03*
Y-16511D03*
D03*
Y-6511D03*
D03*
Y3489D03*
D03*
Y13489D03*
D03*
Y23489D03*
X1474931Y-36511D03*
Y-26511D03*
D03*
Y-16511D03*
D03*
Y-6511D03*
Y3489D03*
Y-6511D03*
Y3489D03*
Y13489D03*
Y23489D03*
Y13489D03*
X1499931Y-36511D03*
Y-26511D03*
D03*
Y-16511D03*
D03*
Y-6511D03*
Y3489D03*
Y-6511D03*
Y3489D03*
Y13489D03*
Y23489D03*
Y13489D03*
X1565236Y184783D03*
Y264035D03*
G54D97*
X1249473Y140119D03*
X1249959Y153904D03*
X1252193Y137419D03*
X1256530Y160252D03*
G54D88*
X948474Y1645870D03*
X985286D03*
G54D79*
X828780Y1694890D03*
Y1684890D03*
X818780Y1694890D03*
Y1684890D03*
X828780Y1704890D03*
X818780D03*
X828780Y1714890D03*
X818780D03*
X853780Y1694890D03*
Y1684890D03*
Y1704890D03*
Y1714890D03*
X863780Y1694890D03*
Y1684890D03*
Y1704890D03*
Y1714890D03*
X888780Y1684890D03*
Y1694890D03*
Y1704890D03*
Y1714890D03*
X898780Y1684890D03*
Y1694890D03*
Y1704890D03*
Y1714890D03*
X918780Y1684890D03*
Y1694890D03*
Y1704890D03*
Y1714890D03*
X928780Y1684890D03*
X938780D03*
X928780Y1694890D03*
X938780D03*
X928780Y1704890D03*
X938780D03*
X928780Y1714890D03*
X958780Y1694890D03*
Y1684890D03*
Y1704890D03*
Y1714890D03*
X968780Y1694890D03*
Y1684890D03*
Y1704890D03*
Y1714890D03*
X993780Y1684890D03*
Y1694890D03*
X1003780Y1684890D03*
Y1694890D03*
X993780Y1704890D03*
Y1714890D03*
X1003780Y1704890D03*
Y1714890D03*
X1028780Y1684890D03*
Y1694890D03*
X1038780Y1684890D03*
Y1694890D03*
X1028780Y1704890D03*
Y1714890D03*
X1038780Y1704890D03*
Y1714890D03*
G54D98*
X1247638Y269488D03*
X1405118Y112008D03*
X1766929Y1714960D03*
G54D89*
X986830Y-21500D03*
Y8500D03*
X1296222Y-31511D03*
Y-11511D03*
Y8489D03*
X1488581Y-31511D03*
Y-11511D03*
Y8489D03*
G54D99*
X1254292Y139518D03*
X1251572Y142218D03*
X1258629Y162351D03*
X1252058Y156003D03*
M02*
